FILE_TYPE = MACRO_DRAWING;
SET COLOR_WIRE YELLOW;
SET COLOR_PROP ORANGE;
SET COLOR_DOT WHITE;
SET COLOR_ARC YELLOW;
SET COLOR_BODY GREEN;
SET COLOR_NOTE PURPLE;
SET PROP_DISPLAY VALUE;
SET PAGE_NUMBER P101;
FORCEADD VCC_CORE..1
(-8700 3675);
FORCEPROP 3 LASTPIN (-8700 3625) SIG_NAME P3V3_STBY\g
J 0
(-8690 3635);
DISPLAY 0.659574 (-8690 3635);
PAINT MONO (-8690 3635);
DISPLAY INVISIBLE (-8690 3635);
FORCEPROP 1 LAST HDL_POWER P3V3_STBY
J 1
(-8700 3725);
DISPLAY 0.489362 (-8700 3725);
PAINT GREEN (-8700 3725);
FORCEPROP 2 LAST CDS_LIB mstr_symbols
J 0
(-8700 3675);
PAINT MONO (-8700 3675);
DISPLAY INVISIBLE (-8700 3675);
FORCEPROP 1 LAST PATH I1
J 0
(-8650 3700);
DISPLAY 0.872340 (-8650 3700);
PAINT AQUA (-8650 3700);
DISPLAY INVISIBLE (-8650 3700);
FORCEPROP 0 LAST VOLTAGE 3.3
J 0
(-8975 3825);
DISPLAY 1.021277 (-8975 3825);
PAINT SKYBLUE (-8975 3825);
DISPLAY INVISIBLE (-8975 3825);
FORCEPROP 2 LAST ROOM PVCCINFAON_CPU1_CTRL
J 0
(-8700 3775);
DISPLAY 0.808511 (-8700 3775);
PAINT RED (-8700 3775);
DISPLAY INVISIBLE (-8700 3775);
FORCEADD OFFPAGE..6
(-8475 3850);
FORCEPROP 2 LAST $XR0 41 
J 0
(-8754 3850);
DISPLAY 0.638298 (-8754 3850);
PAINT MONO (-8754 3850);
FORCEPROP 2 LAST PATH I10
J 0
(-8750 3900);
DISPLAY 1.021277 (-8750 3900);
DISPLAY INVISIBLE (-8750 3900);
FORCEPROP 1 LAST COMMENT_BODY TRUE
J 0
(-8375 3775);
DISPLAY 0.872340 (-8375 3775);
PAINT GREEN (-8375 3775);
DISPLAY INVISIBLE (-8375 3775);
FORCEPROP 1 LAST OFFPAGE TRUE
J 0
(-8150 3725);
DISPLAY 0.872340 (-8150 3725);
PAINT GREEN (-8150 3725);
DISPLAY INVISIBLE (-8150 3725);
FORCEPROP 2 LAST CDS_LIB mstr_standard
J 0
(-8475 3850);
DISPLAY 0.723404 (-8475 3850);
PAINT MONO (-8475 3850);
DISPLAY INVISIBLE (-8475 3850);
FORCEADD TAP..1
(-6175 4450);
FORCEPROP 3 LASTPIN (-6225 4450) SIG_NAME M_E_CPU1_SA_DQ<7>
J 0
(-6215 4460);
DISPLAY 0.659574 (-6215 4460);
PAINT MONO (-6215 4460);
DISPLAY INVISIBLE (-6215 4460);
FORCEPROP 1 LASTPIN (-6225 4450) BN 7
J 0
(-6237 4458);
DISPLAY 0.489362 (-6237 4458);
PAINT GREEN (-6237 4458);
FORCEPROP 2 LAST CDS_LIB mstr_standard
J 0
(-6175 4450);
DISPLAY 0.723404 (-6175 4450);
PAINT MONO (-6175 4450);
DISPLAY INVISIBLE (-6175 4450);
FORCEPROP 1 LAST BODY_TYPE PLUMBING
J 0
(-6175 4500);
DISPLAY 0.872340 (-6175 4500);
PAINT GREEN (-6175 4500);
DISPLAY INVISIBLE (-6175 4500);
FORCEPROP 1 LAST HDL_TAP TRUE
J 0
(-5850 4325);
DISPLAY 0.872340 (-5850 4325);
DISPLAY INVISIBLE (-5850 4325);
FORCEPROP 1 LAST PATH I100
J 0
(-6177 4450);
DISPLAY 0.872340 (-6177 4450);
PAINT GREEN (-6177 4450);
DISPLAY INVISIBLE (-6177 4450);
FORCEADD TAP..1
(-6175 4500);
FORCEPROP 3 LASTPIN (-6225 4500) SIG_NAME M_E_CPU1_SA_DQ<8>
J 0
(-6215 4510);
DISPLAY 0.659574 (-6215 4510);
PAINT MONO (-6215 4510);
DISPLAY INVISIBLE (-6215 4510);
FORCEPROP 1 LASTPIN (-6225 4500) BN 8
J 0
(-6237 4508);
DISPLAY 0.489362 (-6237 4508);
PAINT GREEN (-6237 4508);
FORCEPROP 2 LAST CDS_LIB mstr_standard
J 0
(-6175 4500);
DISPLAY 0.723404 (-6175 4500);
PAINT MONO (-6175 4500);
DISPLAY INVISIBLE (-6175 4500);
FORCEPROP 1 LAST BODY_TYPE PLUMBING
J 0
(-6175 4550);
DISPLAY 0.872340 (-6175 4550);
PAINT GREEN (-6175 4550);
DISPLAY INVISIBLE (-6175 4550);
FORCEPROP 1 LAST HDL_TAP TRUE
J 0
(-5850 4375);
DISPLAY 0.872340 (-5850 4375);
DISPLAY INVISIBLE (-5850 4375);
FORCEPROP 1 LAST PATH I101
J 0
(-6177 4500);
DISPLAY 0.872340 (-6177 4500);
PAINT GREEN (-6177 4500);
DISPLAY INVISIBLE (-6177 4500);
FORCEADD TAP..1
(-6175 4550);
FORCEPROP 3 LASTPIN (-6225 4550) SIG_NAME M_E_CPU1_SA_DQ<9>
J 0
(-6215 4560);
DISPLAY 0.659574 (-6215 4560);
PAINT MONO (-6215 4560);
DISPLAY INVISIBLE (-6215 4560);
FORCEPROP 1 LASTPIN (-6225 4550) BN 9
J 0
(-6237 4558);
DISPLAY 0.489362 (-6237 4558);
PAINT GREEN (-6237 4558);
FORCEPROP 2 LAST CDS_LIB mstr_standard
J 0
(-6175 4550);
DISPLAY 0.723404 (-6175 4550);
PAINT MONO (-6175 4550);
DISPLAY INVISIBLE (-6175 4550);
FORCEPROP 1 LAST BODY_TYPE PLUMBING
J 0
(-6175 4600);
DISPLAY 0.872340 (-6175 4600);
PAINT GREEN (-6175 4600);
DISPLAY INVISIBLE (-6175 4600);
FORCEPROP 1 LAST HDL_TAP TRUE
J 0
(-5850 4425);
DISPLAY 0.872340 (-5850 4425);
DISPLAY INVISIBLE (-5850 4425);
FORCEPROP 1 LAST PATH I102
J 0
(-6177 4550);
DISPLAY 0.872340 (-6177 4550);
PAINT GREEN (-6177 4550);
DISPLAY INVISIBLE (-6177 4550);
FORCEADD TAP..1
(-6175 4650);
FORCEPROP 3 LASTPIN (-6225 4650) SIG_NAME M_E_CPU1_SA_DQ<11>
J 0
(-6215 4660);
DISPLAY 0.659574 (-6215 4660);
PAINT MONO (-6215 4660);
DISPLAY INVISIBLE (-6215 4660);
FORCEPROP 1 LASTPIN (-6225 4650) BN 11
J 0
(-6237 4658);
DISPLAY 0.489362 (-6237 4658);
PAINT GREEN (-6237 4658);
FORCEPROP 2 LAST CDS_LIB mstr_standard
J 0
(-6175 4650);
DISPLAY 0.723404 (-6175 4650);
PAINT MONO (-6175 4650);
DISPLAY INVISIBLE (-6175 4650);
FORCEPROP 1 LAST BODY_TYPE PLUMBING
J 0
(-6175 4700);
DISPLAY 0.872340 (-6175 4700);
PAINT GREEN (-6175 4700);
DISPLAY INVISIBLE (-6175 4700);
FORCEPROP 1 LAST HDL_TAP TRUE
J 0
(-5850 4525);
DISPLAY 0.872340 (-5850 4525);
DISPLAY INVISIBLE (-5850 4525);
FORCEPROP 1 LAST PATH I103
J 0
(-6177 4650);
DISPLAY 0.872340 (-6177 4650);
PAINT GREEN (-6177 4650);
DISPLAY INVISIBLE (-6177 4650);
FORCEADD TAP..1
(-6175 4600);
FORCEPROP 3 LASTPIN (-6225 4600) SIG_NAME M_E_CPU1_SA_DQ<10>
J 0
(-6215 4610);
DISPLAY 0.659574 (-6215 4610);
PAINT MONO (-6215 4610);
DISPLAY INVISIBLE (-6215 4610);
FORCEPROP 1 LASTPIN (-6225 4600) BN 10
J 0
(-6237 4608);
DISPLAY 0.489362 (-6237 4608);
PAINT GREEN (-6237 4608);
FORCEPROP 2 LAST CDS_LIB mstr_standard
J 0
(-6175 4600);
DISPLAY 0.723404 (-6175 4600);
PAINT MONO (-6175 4600);
DISPLAY INVISIBLE (-6175 4600);
FORCEPROP 1 LAST BODY_TYPE PLUMBING
J 0
(-6175 4650);
DISPLAY 0.872340 (-6175 4650);
PAINT GREEN (-6175 4650);
DISPLAY INVISIBLE (-6175 4650);
FORCEPROP 1 LAST HDL_TAP TRUE
J 0
(-5850 4475);
DISPLAY 0.872340 (-5850 4475);
DISPLAY INVISIBLE (-5850 4475);
FORCEPROP 1 LAST PATH I104
J 0
(-6177 4600);
DISPLAY 0.872340 (-6177 4600);
PAINT GREEN (-6177 4600);
DISPLAY INVISIBLE (-6177 4600);
FORCEADD TAP..1
(-6175 4800);
FORCEPROP 3 LASTPIN (-6225 4800) SIG_NAME M_E_CPU1_SA_DQ<14>
J 0
(-6215 4810);
DISPLAY 0.659574 (-6215 4810);
PAINT MONO (-6215 4810);
DISPLAY INVISIBLE (-6215 4810);
FORCEPROP 1 LASTPIN (-6225 4800) BN 14
J 0
(-6237 4808);
DISPLAY 0.489362 (-6237 4808);
PAINT GREEN (-6237 4808);
FORCEPROP 2 LAST CDS_LIB mstr_standard
J 0
(-6175 4800);
DISPLAY 0.723404 (-6175 4800);
PAINT MONO (-6175 4800);
DISPLAY INVISIBLE (-6175 4800);
FORCEPROP 1 LAST BODY_TYPE PLUMBING
J 0
(-6175 4850);
DISPLAY 0.872340 (-6175 4850);
PAINT GREEN (-6175 4850);
DISPLAY INVISIBLE (-6175 4850);
FORCEPROP 1 LAST HDL_TAP TRUE
J 0
(-5850 4675);
DISPLAY 0.872340 (-5850 4675);
DISPLAY INVISIBLE (-5850 4675);
FORCEPROP 1 LAST PATH I105
J 0
(-6177 4800);
DISPLAY 0.872340 (-6177 4800);
PAINT GREEN (-6177 4800);
DISPLAY INVISIBLE (-6177 4800);
FORCEADD TAP..1
(-6175 4750);
FORCEPROP 3 LASTPIN (-6225 4750) SIG_NAME M_E_CPU1_SA_DQ<13>
J 0
(-6215 4760);
DISPLAY 0.659574 (-6215 4760);
PAINT MONO (-6215 4760);
DISPLAY INVISIBLE (-6215 4760);
FORCEPROP 1 LASTPIN (-6225 4750) BN 13
J 0
(-6237 4758);
DISPLAY 0.489362 (-6237 4758);
PAINT GREEN (-6237 4758);
FORCEPROP 2 LAST CDS_LIB mstr_standard
J 0
(-6175 4750);
DISPLAY 0.723404 (-6175 4750);
PAINT MONO (-6175 4750);
DISPLAY INVISIBLE (-6175 4750);
FORCEPROP 1 LAST BODY_TYPE PLUMBING
J 0
(-6175 4800);
DISPLAY 0.872340 (-6175 4800);
PAINT GREEN (-6175 4800);
DISPLAY INVISIBLE (-6175 4800);
FORCEPROP 1 LAST HDL_TAP TRUE
J 0
(-5850 4625);
DISPLAY 0.872340 (-5850 4625);
DISPLAY INVISIBLE (-5850 4625);
FORCEPROP 1 LAST PATH I106
J 0
(-6177 4750);
DISPLAY 0.872340 (-6177 4750);
PAINT GREEN (-6177 4750);
DISPLAY INVISIBLE (-6177 4750);
FORCEADD TAP..1
(-6175 4700);
FORCEPROP 3 LASTPIN (-6225 4700) SIG_NAME M_E_CPU1_SA_DQ<12>
J 0
(-6215 4710);
DISPLAY 0.659574 (-6215 4710);
PAINT MONO (-6215 4710);
DISPLAY INVISIBLE (-6215 4710);
FORCEPROP 1 LASTPIN (-6225 4700) BN 12
J 0
(-6237 4708);
DISPLAY 0.489362 (-6237 4708);
PAINT GREEN (-6237 4708);
FORCEPROP 2 LAST CDS_LIB mstr_standard
J 0
(-6175 4700);
DISPLAY 0.723404 (-6175 4700);
PAINT MONO (-6175 4700);
DISPLAY INVISIBLE (-6175 4700);
FORCEPROP 1 LAST BODY_TYPE PLUMBING
J 0
(-6175 4750);
DISPLAY 0.872340 (-6175 4750);
PAINT GREEN (-6175 4750);
DISPLAY INVISIBLE (-6175 4750);
FORCEPROP 1 LAST HDL_TAP TRUE
J 0
(-5850 4575);
DISPLAY 0.872340 (-5850 4575);
DISPLAY INVISIBLE (-5850 4575);
FORCEPROP 1 LAST PATH I107
J 0
(-6177 4700);
DISPLAY 0.872340 (-6177 4700);
PAINT GREEN (-6177 4700);
DISPLAY INVISIBLE (-6177 4700);
FORCEADD TAP..1
(-6175 4850);
FORCEPROP 3 LASTPIN (-6225 4850) SIG_NAME M_E_CPU1_SA_DQ<15>
J 0
(-6215 4860);
DISPLAY 0.659574 (-6215 4860);
PAINT MONO (-6215 4860);
DISPLAY INVISIBLE (-6215 4860);
FORCEPROP 1 LASTPIN (-6225 4850) BN 15
J 0
(-6237 4858);
DISPLAY 0.489362 (-6237 4858);
PAINT GREEN (-6237 4858);
FORCEPROP 2 LAST CDS_LIB mstr_standard
J 0
(-6175 4850);
DISPLAY 0.723404 (-6175 4850);
PAINT MONO (-6175 4850);
DISPLAY INVISIBLE (-6175 4850);
FORCEPROP 1 LAST BODY_TYPE PLUMBING
J 0
(-6175 4900);
DISPLAY 0.872340 (-6175 4900);
PAINT GREEN (-6175 4900);
DISPLAY INVISIBLE (-6175 4900);
FORCEPROP 1 LAST HDL_TAP TRUE
J 0
(-5850 4725);
DISPLAY 0.872340 (-5850 4725);
DISPLAY INVISIBLE (-5850 4725);
FORCEPROP 1 LAST PATH I108
J 0
(-6177 4850);
DISPLAY 0.872340 (-6177 4850);
PAINT GREEN (-6177 4850);
DISPLAY INVISIBLE (-6177 4850);
FORCEADD TAP..1
(-6175 4900);
FORCEPROP 3 LASTPIN (-6225 4900) SIG_NAME M_E_CPU1_SA_DQ<16>
J 0
(-6215 4910);
DISPLAY 0.659574 (-6215 4910);
PAINT MONO (-6215 4910);
DISPLAY INVISIBLE (-6215 4910);
FORCEPROP 1 LASTPIN (-6225 4900) BN 16
J 0
(-6237 4908);
DISPLAY 0.489362 (-6237 4908);
PAINT GREEN (-6237 4908);
FORCEPROP 2 LAST CDS_LIB mstr_standard
J 0
(-6175 4900);
DISPLAY 0.723404 (-6175 4900);
PAINT MONO (-6175 4900);
DISPLAY INVISIBLE (-6175 4900);
FORCEPROP 1 LAST BODY_TYPE PLUMBING
J 0
(-6175 4950);
DISPLAY 0.872340 (-6175 4950);
PAINT GREEN (-6175 4950);
DISPLAY INVISIBLE (-6175 4950);
FORCEPROP 1 LAST HDL_TAP TRUE
J 0
(-5850 4775);
DISPLAY 0.872340 (-5850 4775);
DISPLAY INVISIBLE (-5850 4775);
FORCEPROP 1 LAST PATH I109
J 0
(-6177 4900);
DISPLAY 0.872340 (-6177 4900);
PAINT GREEN (-6177 4900);
DISPLAY INVISIBLE (-6177 4900);
FORCEADD TAP..1
R 2
(-7875 3450);
FORCEPROP 3 LASTPIN (-7825 3450) SIG_NAME M_E_CPU1_SB_CB<0>
J 0
(-7815 3460);
DISPLAY 0.659574 (-7815 3460);
PAINT MONO (-7815 3460);
DISPLAY INVISIBLE (-7815 3460);
FORCEPROP 1 LASTPIN (-7825 3450) BN 0
J 2
(-7813 3458);
DISPLAY 0.489362 (-7813 3458);
PAINT GREEN (-7813 3458);
FORCEPROP 2 LAST CDS_LIB mstr_standard
J 0
(-7875 3450);
DISPLAY 0.723404 (-7875 3450);
PAINT MONO (-7875 3450);
DISPLAY INVISIBLE (-7875 3450);
FORCEPROP 1 LAST BODY_TYPE PLUMBING
J 2
(-7875 3500);
DISPLAY 0.872340 (-7875 3500);
PAINT GREEN (-7875 3500);
DISPLAY INVISIBLE (-7875 3500);
FORCEPROP 1 LAST HDL_TAP TRUE
J 2
(-8200 3325);
DISPLAY 0.872340 (-8200 3325);
DISPLAY INVISIBLE (-8200 3325);
FORCEPROP 1 LAST PATH I11
J 2
(-7873 3450);
DISPLAY 0.872340 (-7873 3450);
PAINT GREEN (-7873 3450);
DISPLAY INVISIBLE (-7873 3450);
FORCEADD TAP..1
(-6175 4950);
FORCEPROP 3 LASTPIN (-6225 4950) SIG_NAME M_E_CPU1_SA_DQ<17>
J 0
(-6215 4960);
DISPLAY 0.659574 (-6215 4960);
PAINT MONO (-6215 4960);
DISPLAY INVISIBLE (-6215 4960);
FORCEPROP 1 LASTPIN (-6225 4950) BN 17
J 0
(-6237 4958);
DISPLAY 0.489362 (-6237 4958);
PAINT GREEN (-6237 4958);
FORCEPROP 2 LAST CDS_LIB mstr_standard
J 0
(-6175 4950);
DISPLAY 0.723404 (-6175 4950);
PAINT MONO (-6175 4950);
DISPLAY INVISIBLE (-6175 4950);
FORCEPROP 1 LAST BODY_TYPE PLUMBING
J 0
(-6175 5000);
DISPLAY 0.872340 (-6175 5000);
PAINT GREEN (-6175 5000);
DISPLAY INVISIBLE (-6175 5000);
FORCEPROP 1 LAST HDL_TAP TRUE
J 0
(-5850 4825);
DISPLAY 0.872340 (-5850 4825);
DISPLAY INVISIBLE (-5850 4825);
FORCEPROP 1 LAST PATH I110
J 0
(-6177 4950);
DISPLAY 0.872340 (-6177 4950);
PAINT GREEN (-6177 4950);
DISPLAY INVISIBLE (-6177 4950);
FORCEADD TAP..1
(-6175 5000);
FORCEPROP 3 LASTPIN (-6225 5000) SIG_NAME M_E_CPU1_SA_DQ<18>
J 0
(-6215 5010);
DISPLAY 0.659574 (-6215 5010);
PAINT MONO (-6215 5010);
DISPLAY INVISIBLE (-6215 5010);
FORCEPROP 1 LASTPIN (-6225 5000) BN 18
J 0
(-6237 5008);
DISPLAY 0.489362 (-6237 5008);
PAINT GREEN (-6237 5008);
FORCEPROP 2 LAST CDS_LIB mstr_standard
J 0
(-6175 5000);
DISPLAY 0.723404 (-6175 5000);
PAINT MONO (-6175 5000);
DISPLAY INVISIBLE (-6175 5000);
FORCEPROP 1 LAST BODY_TYPE PLUMBING
J 0
(-6175 5050);
DISPLAY 0.872340 (-6175 5050);
PAINT GREEN (-6175 5050);
DISPLAY INVISIBLE (-6175 5050);
FORCEPROP 1 LAST HDL_TAP TRUE
J 0
(-5850 4875);
DISPLAY 0.872340 (-5850 4875);
DISPLAY INVISIBLE (-5850 4875);
FORCEPROP 1 LAST PATH I111
J 0
(-6177 5000);
DISPLAY 0.872340 (-6177 5000);
PAINT GREEN (-6177 5000);
DISPLAY INVISIBLE (-6177 5000);
FORCEADD TAP..1
(-6175 5050);
FORCEPROP 3 LASTPIN (-6225 5050) SIG_NAME M_E_CPU1_SA_DQ<19>
J 0
(-6215 5060);
DISPLAY 0.659574 (-6215 5060);
PAINT MONO (-6215 5060);
DISPLAY INVISIBLE (-6215 5060);
FORCEPROP 1 LASTPIN (-6225 5050) BN 19
J 0
(-6237 5058);
DISPLAY 0.489362 (-6237 5058);
PAINT GREEN (-6237 5058);
FORCEPROP 2 LAST CDS_LIB mstr_standard
J 0
(-6175 5050);
DISPLAY 0.723404 (-6175 5050);
PAINT MONO (-6175 5050);
DISPLAY INVISIBLE (-6175 5050);
FORCEPROP 1 LAST BODY_TYPE PLUMBING
J 0
(-6175 5100);
DISPLAY 0.872340 (-6175 5100);
PAINT GREEN (-6175 5100);
DISPLAY INVISIBLE (-6175 5100);
FORCEPROP 1 LAST HDL_TAP TRUE
J 0
(-5850 4925);
DISPLAY 0.872340 (-5850 4925);
DISPLAY INVISIBLE (-5850 4925);
FORCEPROP 1 LAST PATH I112
J 0
(-6177 5050);
DISPLAY 0.872340 (-6177 5050);
PAINT GREEN (-6177 5050);
DISPLAY INVISIBLE (-6177 5050);
FORCEADD TAP..1
(-6175 5100);
FORCEPROP 3 LASTPIN (-6225 5100) SIG_NAME M_E_CPU1_SA_DQ<20>
J 0
(-6215 5110);
DISPLAY 0.659574 (-6215 5110);
PAINT MONO (-6215 5110);
DISPLAY INVISIBLE (-6215 5110);
FORCEPROP 1 LASTPIN (-6225 5100) BN 20
J 0
(-6237 5108);
DISPLAY 0.489362 (-6237 5108);
PAINT GREEN (-6237 5108);
FORCEPROP 2 LAST CDS_LIB mstr_standard
J 0
(-6175 5100);
DISPLAY 0.723404 (-6175 5100);
PAINT MONO (-6175 5100);
DISPLAY INVISIBLE (-6175 5100);
FORCEPROP 1 LAST BODY_TYPE PLUMBING
J 0
(-6175 5150);
DISPLAY 0.872340 (-6175 5150);
PAINT GREEN (-6175 5150);
DISPLAY INVISIBLE (-6175 5150);
FORCEPROP 1 LAST HDL_TAP TRUE
J 0
(-5850 4975);
DISPLAY 0.872340 (-5850 4975);
DISPLAY INVISIBLE (-5850 4975);
FORCEPROP 1 LAST PATH I113
J 0
(-6177 5100);
DISPLAY 0.872340 (-6177 5100);
PAINT GREEN (-6177 5100);
DISPLAY INVISIBLE (-6177 5100);
FORCEADD TAP..1
(-6175 5150);
FORCEPROP 3 LASTPIN (-6225 5150) SIG_NAME M_E_CPU1_SA_DQ<21>
J 0
(-6215 5160);
DISPLAY 0.659574 (-6215 5160);
PAINT MONO (-6215 5160);
DISPLAY INVISIBLE (-6215 5160);
FORCEPROP 1 LASTPIN (-6225 5150) BN 21
J 0
(-6237 5158);
DISPLAY 0.489362 (-6237 5158);
PAINT GREEN (-6237 5158);
FORCEPROP 2 LAST CDS_LIB mstr_standard
J 0
(-6175 5150);
DISPLAY 0.723404 (-6175 5150);
PAINT MONO (-6175 5150);
DISPLAY INVISIBLE (-6175 5150);
FORCEPROP 1 LAST BODY_TYPE PLUMBING
J 0
(-6175 5200);
DISPLAY 0.872340 (-6175 5200);
PAINT GREEN (-6175 5200);
DISPLAY INVISIBLE (-6175 5200);
FORCEPROP 1 LAST HDL_TAP TRUE
J 0
(-5850 5025);
DISPLAY 0.872340 (-5850 5025);
DISPLAY INVISIBLE (-5850 5025);
FORCEPROP 1 LAST PATH I114
J 0
(-6177 5150);
DISPLAY 0.872340 (-6177 5150);
PAINT GREEN (-6177 5150);
DISPLAY INVISIBLE (-6177 5150);
FORCEADD TAP..1
(-6175 5250);
FORCEPROP 3 LASTPIN (-6225 5250) SIG_NAME M_E_CPU1_SA_DQ<23>
J 0
(-6215 5260);
DISPLAY 0.659574 (-6215 5260);
PAINT MONO (-6215 5260);
DISPLAY INVISIBLE (-6215 5260);
FORCEPROP 1 LASTPIN (-6225 5250) BN 23
J 0
(-6237 5258);
DISPLAY 0.489362 (-6237 5258);
PAINT GREEN (-6237 5258);
FORCEPROP 2 LAST CDS_LIB mstr_standard
J 0
(-6175 5250);
DISPLAY 0.723404 (-6175 5250);
PAINT MONO (-6175 5250);
DISPLAY INVISIBLE (-6175 5250);
FORCEPROP 1 LAST BODY_TYPE PLUMBING
J 0
(-6175 5300);
DISPLAY 0.872340 (-6175 5300);
PAINT GREEN (-6175 5300);
DISPLAY INVISIBLE (-6175 5300);
FORCEPROP 1 LAST HDL_TAP TRUE
J 0
(-5850 5125);
DISPLAY 0.872340 (-5850 5125);
DISPLAY INVISIBLE (-5850 5125);
FORCEPROP 1 LAST PATH I115
J 0
(-6177 5250);
DISPLAY 0.872340 (-6177 5250);
PAINT GREEN (-6177 5250);
DISPLAY INVISIBLE (-6177 5250);
FORCEADD TAP..1
(-6175 5200);
FORCEPROP 3 LASTPIN (-6225 5200) SIG_NAME M_E_CPU1_SA_DQ<22>
J 0
(-6215 5210);
DISPLAY 0.659574 (-6215 5210);
PAINT MONO (-6215 5210);
DISPLAY INVISIBLE (-6215 5210);
FORCEPROP 1 LASTPIN (-6225 5200) BN 22
J 0
(-6237 5208);
DISPLAY 0.489362 (-6237 5208);
PAINT GREEN (-6237 5208);
FORCEPROP 2 LAST CDS_LIB mstr_standard
J 0
(-6175 5200);
DISPLAY 0.723404 (-6175 5200);
PAINT MONO (-6175 5200);
DISPLAY INVISIBLE (-6175 5200);
FORCEPROP 1 LAST BODY_TYPE PLUMBING
J 0
(-6175 5250);
DISPLAY 0.872340 (-6175 5250);
PAINT GREEN (-6175 5250);
DISPLAY INVISIBLE (-6175 5250);
FORCEPROP 1 LAST HDL_TAP TRUE
J 0
(-5850 5075);
DISPLAY 0.872340 (-5850 5075);
DISPLAY INVISIBLE (-5850 5075);
FORCEPROP 1 LAST PATH I116
J 0
(-6177 5200);
DISPLAY 0.872340 (-6177 5200);
PAINT GREEN (-6177 5200);
DISPLAY INVISIBLE (-6177 5200);
FORCEADD TAP..1
(-6175 5300);
FORCEPROP 3 LASTPIN (-6225 5300) SIG_NAME M_E_CPU1_SA_DQ<24>
J 0
(-6215 5310);
DISPLAY 0.659574 (-6215 5310);
PAINT MONO (-6215 5310);
DISPLAY INVISIBLE (-6215 5310);
FORCEPROP 1 LASTPIN (-6225 5300) BN 24
J 0
(-6237 5308);
DISPLAY 0.489362 (-6237 5308);
PAINT GREEN (-6237 5308);
FORCEPROP 2 LAST CDS_LIB mstr_standard
J 0
(-6175 5300);
DISPLAY 0.723404 (-6175 5300);
PAINT MONO (-6175 5300);
DISPLAY INVISIBLE (-6175 5300);
FORCEPROP 1 LAST BODY_TYPE PLUMBING
J 0
(-6175 5350);
DISPLAY 0.872340 (-6175 5350);
PAINT GREEN (-6175 5350);
DISPLAY INVISIBLE (-6175 5350);
FORCEPROP 1 LAST HDL_TAP TRUE
J 0
(-5850 5175);
DISPLAY 0.872340 (-5850 5175);
DISPLAY INVISIBLE (-5850 5175);
FORCEPROP 1 LAST PATH I117
J 0
(-6177 5300);
DISPLAY 0.872340 (-6177 5300);
PAINT GREEN (-6177 5300);
DISPLAY INVISIBLE (-6177 5300);
FORCEADD TAP..1
(-6175 5450);
FORCEPROP 3 LASTPIN (-6225 5450) SIG_NAME M_E_CPU1_SA_DQ<27>
J 0
(-6215 5460);
DISPLAY 0.659574 (-6215 5460);
PAINT MONO (-6215 5460);
DISPLAY INVISIBLE (-6215 5460);
FORCEPROP 1 LASTPIN (-6225 5450) BN 27
J 0
(-6237 5458);
DISPLAY 0.489362 (-6237 5458);
PAINT GREEN (-6237 5458);
FORCEPROP 2 LAST CDS_LIB mstr_standard
J 0
(-6175 5450);
DISPLAY 0.723404 (-6175 5450);
PAINT MONO (-6175 5450);
DISPLAY INVISIBLE (-6175 5450);
FORCEPROP 1 LAST BODY_TYPE PLUMBING
J 0
(-6175 5500);
DISPLAY 0.872340 (-6175 5500);
PAINT GREEN (-6175 5500);
DISPLAY INVISIBLE (-6175 5500);
FORCEPROP 1 LAST HDL_TAP TRUE
J 0
(-5850 5325);
DISPLAY 0.872340 (-5850 5325);
DISPLAY INVISIBLE (-5850 5325);
FORCEPROP 1 LAST PATH I118
J 0
(-6177 5450);
DISPLAY 0.872340 (-6177 5450);
PAINT GREEN (-6177 5450);
DISPLAY INVISIBLE (-6177 5450);
FORCEADD TAP..1
(-6175 5400);
FORCEPROP 3 LASTPIN (-6225 5400) SIG_NAME M_E_CPU1_SA_DQ<26>
J 0
(-6215 5410);
DISPLAY 0.659574 (-6215 5410);
PAINT MONO (-6215 5410);
DISPLAY INVISIBLE (-6215 5410);
FORCEPROP 1 LASTPIN (-6225 5400) BN 26
J 0
(-6237 5408);
DISPLAY 0.489362 (-6237 5408);
PAINT GREEN (-6237 5408);
FORCEPROP 2 LAST CDS_LIB mstr_standard
J 0
(-6175 5400);
DISPLAY 0.723404 (-6175 5400);
PAINT MONO (-6175 5400);
DISPLAY INVISIBLE (-6175 5400);
FORCEPROP 1 LAST BODY_TYPE PLUMBING
J 0
(-6175 5450);
DISPLAY 0.872340 (-6175 5450);
PAINT GREEN (-6175 5450);
DISPLAY INVISIBLE (-6175 5450);
FORCEPROP 1 LAST HDL_TAP TRUE
J 0
(-5850 5275);
DISPLAY 0.872340 (-5850 5275);
DISPLAY INVISIBLE (-5850 5275);
FORCEPROP 1 LAST PATH I119
J 0
(-6177 5400);
DISPLAY 0.872340 (-6177 5400);
PAINT GREEN (-6177 5400);
DISPLAY INVISIBLE (-6177 5400);
FORCEADD TAP..1
R 2
(-7875 3500);
FORCEPROP 3 LASTPIN (-7825 3500) SIG_NAME M_E_CPU1_SB_CB<1>
J 0
(-7815 3510);
DISPLAY 0.659574 (-7815 3510);
PAINT MONO (-7815 3510);
DISPLAY INVISIBLE (-7815 3510);
FORCEPROP 1 LASTPIN (-7825 3500) BN 1
J 2
(-7813 3508);
DISPLAY 0.489362 (-7813 3508);
PAINT GREEN (-7813 3508);
FORCEPROP 2 LAST CDS_LIB mstr_standard
J 0
(-7875 3500);
DISPLAY 0.723404 (-7875 3500);
PAINT MONO (-7875 3500);
DISPLAY INVISIBLE (-7875 3500);
FORCEPROP 1 LAST BODY_TYPE PLUMBING
J 2
(-7875 3550);
DISPLAY 0.872340 (-7875 3550);
PAINT GREEN (-7875 3550);
DISPLAY INVISIBLE (-7875 3550);
FORCEPROP 1 LAST HDL_TAP TRUE
J 2
(-8200 3375);
DISPLAY 0.872340 (-8200 3375);
DISPLAY INVISIBLE (-8200 3375);
FORCEPROP 1 LAST PATH I12
J 2
(-7873 3500);
DISPLAY 0.872340 (-7873 3500);
PAINT GREEN (-7873 3500);
DISPLAY INVISIBLE (-7873 3500);
FORCEADD TAP..1
(-6175 5350);
FORCEPROP 3 LASTPIN (-6225 5350) SIG_NAME M_E_CPU1_SA_DQ<25>
J 0
(-6215 5360);
DISPLAY 0.659574 (-6215 5360);
PAINT MONO (-6215 5360);
DISPLAY INVISIBLE (-6215 5360);
FORCEPROP 1 LASTPIN (-6225 5350) BN 25
J 0
(-6237 5358);
DISPLAY 0.489362 (-6237 5358);
PAINT GREEN (-6237 5358);
FORCEPROP 2 LAST CDS_LIB mstr_standard
J 0
(-6175 5350);
DISPLAY 0.723404 (-6175 5350);
PAINT MONO (-6175 5350);
DISPLAY INVISIBLE (-6175 5350);
FORCEPROP 1 LAST BODY_TYPE PLUMBING
J 0
(-6175 5400);
DISPLAY 0.872340 (-6175 5400);
PAINT GREEN (-6175 5400);
DISPLAY INVISIBLE (-6175 5400);
FORCEPROP 1 LAST HDL_TAP TRUE
J 0
(-5850 5225);
DISPLAY 0.872340 (-5850 5225);
DISPLAY INVISIBLE (-5850 5225);
FORCEPROP 1 LAST PATH I120
J 0
(-6177 5350);
DISPLAY 0.872340 (-6177 5350);
PAINT GREEN (-6177 5350);
DISPLAY INVISIBLE (-6177 5350);
FORCEADD TAP..1
(-6175 5500);
FORCEPROP 3 LASTPIN (-6225 5500) SIG_NAME M_E_CPU1_SA_DQ<28>
J 0
(-6215 5510);
DISPLAY 0.659574 (-6215 5510);
PAINT MONO (-6215 5510);
DISPLAY INVISIBLE (-6215 5510);
FORCEPROP 1 LASTPIN (-6225 5500) BN 28
J 0
(-6237 5508);
DISPLAY 0.489362 (-6237 5508);
PAINT GREEN (-6237 5508);
FORCEPROP 2 LAST CDS_LIB mstr_standard
J 0
(-6175 5500);
DISPLAY 0.723404 (-6175 5500);
PAINT MONO (-6175 5500);
DISPLAY INVISIBLE (-6175 5500);
FORCEPROP 1 LAST BODY_TYPE PLUMBING
J 0
(-6175 5550);
DISPLAY 0.872340 (-6175 5550);
PAINT GREEN (-6175 5550);
DISPLAY INVISIBLE (-6175 5550);
FORCEPROP 1 LAST HDL_TAP TRUE
J 0
(-5850 5375);
DISPLAY 0.872340 (-5850 5375);
DISPLAY INVISIBLE (-5850 5375);
FORCEPROP 1 LAST PATH I121
J 0
(-6177 5500);
DISPLAY 0.872340 (-6177 5500);
PAINT GREEN (-6177 5500);
DISPLAY INVISIBLE (-6177 5500);
FORCEADD TAP..1
(-6175 5550);
FORCEPROP 3 LASTPIN (-6225 5550) SIG_NAME M_E_CPU1_SA_DQ<29>
J 0
(-6215 5560);
DISPLAY 0.659574 (-6215 5560);
PAINT MONO (-6215 5560);
DISPLAY INVISIBLE (-6215 5560);
FORCEPROP 1 LASTPIN (-6225 5550) BN 29
J 0
(-6237 5558);
DISPLAY 0.489362 (-6237 5558);
PAINT GREEN (-6237 5558);
FORCEPROP 2 LAST CDS_LIB mstr_standard
J 0
(-6175 5550);
DISPLAY 0.723404 (-6175 5550);
PAINT MONO (-6175 5550);
DISPLAY INVISIBLE (-6175 5550);
FORCEPROP 1 LAST BODY_TYPE PLUMBING
J 0
(-6175 5600);
DISPLAY 0.872340 (-6175 5600);
PAINT GREEN (-6175 5600);
DISPLAY INVISIBLE (-6175 5600);
FORCEPROP 1 LAST HDL_TAP TRUE
J 0
(-5850 5425);
DISPLAY 0.872340 (-5850 5425);
DISPLAY INVISIBLE (-5850 5425);
FORCEPROP 1 LAST PATH I122
J 0
(-6177 5550);
DISPLAY 0.872340 (-6177 5550);
PAINT GREEN (-6177 5550);
DISPLAY INVISIBLE (-6177 5550);
FORCEADD TAP..1
(-6175 5650);
FORCEPROP 3 LASTPIN (-6225 5650) SIG_NAME M_E_CPU1_SA_DQ<31>
J 0
(-6215 5660);
DISPLAY 0.659574 (-6215 5660);
PAINT MONO (-6215 5660);
DISPLAY INVISIBLE (-6215 5660);
FORCEPROP 1 LASTPIN (-6225 5650) BN 31
J 0
(-6237 5658);
DISPLAY 0.489362 (-6237 5658);
PAINT GREEN (-6237 5658);
FORCEPROP 2 LAST CDS_LIB mstr_standard
J 0
(-6175 5650);
DISPLAY 0.723404 (-6175 5650);
PAINT MONO (-6175 5650);
DISPLAY INVISIBLE (-6175 5650);
FORCEPROP 1 LAST BODY_TYPE PLUMBING
J 0
(-6175 5700);
DISPLAY 0.872340 (-6175 5700);
PAINT GREEN (-6175 5700);
DISPLAY INVISIBLE (-6175 5700);
FORCEPROP 1 LAST HDL_TAP TRUE
J 0
(-5850 5525);
DISPLAY 0.872340 (-5850 5525);
DISPLAY INVISIBLE (-5850 5525);
FORCEPROP 1 LAST PATH I123
J 0
(-6177 5650);
DISPLAY 0.872340 (-6177 5650);
PAINT GREEN (-6177 5650);
DISPLAY INVISIBLE (-6177 5650);
FORCEADD TAP..1
(-6175 5600);
FORCEPROP 3 LASTPIN (-6225 5600) SIG_NAME M_E_CPU1_SA_DQ<30>
J 0
(-6215 5610);
DISPLAY 0.659574 (-6215 5610);
PAINT MONO (-6215 5610);
DISPLAY INVISIBLE (-6215 5610);
FORCEPROP 1 LASTPIN (-6225 5600) BN 30
J 0
(-6237 5608);
DISPLAY 0.489362 (-6237 5608);
PAINT GREEN (-6237 5608);
FORCEPROP 2 LAST CDS_LIB mstr_standard
J 0
(-6175 5600);
DISPLAY 0.723404 (-6175 5600);
PAINT MONO (-6175 5600);
DISPLAY INVISIBLE (-6175 5600);
FORCEPROP 1 LAST BODY_TYPE PLUMBING
J 0
(-6175 5650);
DISPLAY 0.872340 (-6175 5650);
PAINT GREEN (-6175 5650);
DISPLAY INVISIBLE (-6175 5650);
FORCEPROP 1 LAST HDL_TAP TRUE
J 0
(-5850 5475);
DISPLAY 0.872340 (-5850 5475);
DISPLAY INVISIBLE (-5850 5475);
FORCEPROP 1 LAST PATH I124
J 0
(-6177 5600);
DISPLAY 0.872340 (-6177 5600);
PAINT GREEN (-6177 5600);
DISPLAY INVISIBLE (-6177 5600);
FORCEADD OFFPAGE..3
(-5500 5700);
FORCEPROP 2 LAST $XR0 41 
J 0
(-5286 5700);
DISPLAY 0.638298 (-5286 5700);
PAINT MONO (-5286 5700);
FORCEPROP 2 LAST PATH I125
J 0
(-5275 5750);
DISPLAY 1.021277 (-5275 5750);
DISPLAY INVISIBLE (-5275 5750);
FORCEPROP 1 LAST COMMENT_BODY TRUE
J 0
(-5550 5600);
DISPLAY 0.872340 (-5550 5600);
PAINT GREEN (-5550 5600);
DISPLAY INVISIBLE (-5550 5600);
FORCEPROP 1 LAST OFFPAGE TRUE
J 0
(-5175 5575);
DISPLAY 0.872340 (-5175 5575);
PAINT GREEN (-5175 5575);
DISPLAY INVISIBLE (-5175 5575);
FORCEPROP 2 LAST CDS_LIB mstr_standard
J 0
(-5500 5700);
DISPLAY 0.723404 (-5500 5700);
PAINT MONO (-5500 5700);
DISPLAY INVISIBLE (-5500 5700);
FORCEADD GND..1
(-6575 1250);
FORCEPROP 3 LASTPIN (-6575 1300) SIG_NAME GND\g
J 0
(-6565 1310);
DISPLAY 0.659574 (-6565 1310);
PAINT MONO (-6565 1310);
DISPLAY INVISIBLE (-6565 1310);
FORCEPROP 2 LAST BOM_COST MEM
J 0
(-6675 1325);
DISPLAY 0.808511 (-6675 1325);
DISPLAY INVISIBLE (-6675 1325);
FORCEPROP 1 LAST SIZE 1B
J 0
(-6500 1200);
DISPLAY 0.851064 (-6500 1200);
PAINT GREEN (-6500 1200);
DISPLAY INVISIBLE (-6500 1200);
FORCEPROP 2 LAST CDS_LIB mstr_symbols
J 0
(-6575 1250);
DISPLAY 0.808511 (-6575 1250);
DISPLAY INVISIBLE (-6575 1250);
FORCEPROP 1 LAST BODY_TYPE PLUMBING
J 0
(-6620 1207);
DISPLAY 0.340426 (-6620 1207);
PAINT GREEN (-6620 1207);
DISPLAY INVISIBLE (-6620 1207);
FORCEPROP 1 LAST PATH I126
J 0
(-6500 1250);
DISPLAY 0.872340 (-6500 1250);
PAINT AQUA (-6500 1250);
DISPLAY INVISIBLE (-6500 1250);
FORCEPROP 1 LAST VOLTAGE 0.0
J 0
(-6620 1207);
DISPLAY 0.723404 (-6620 1207);
PAINT SKYBLUE (-6620 1207);
DISPLAY INVISIBLE (-6620 1207);
FORCEPROP 1 LAST HDL_POWER GND
J 0
(-6575 1400);
DISPLAY 0.851064 (-6575 1400);
PAINT GREEN (-6575 1400);
DISPLAY INVISIBLE (-6575 1400);
FORCEADD Q_RES..2
(-6575 1475);
FORCEPROP 1 LAST LOCATION R6
J 0
(-6530 1600);
DISPLAY 0.489362 (-6530 1600);
PAINT SKYBLUE (-6530 1600);
FORCEPROP 2 LAST SEC 1
J 0
(-6525 1700);
DISPLAY 0.808511 (-6525 1700);
PAINT MONO (-6525 1700);
DISPLAY INVISIBLE (-6525 1700);
FORCEPROP 1 LASTPIN (-6575 1575) $PN 1
J 0
(-6570 1537);
DISPLAY 0.489362 (-6570 1537);
PAINT WHITE (-6570 1537);
FORCEPROP 1 LASTPIN (-6575 1375) $PN 2
J 0
(-6570 1385);
DISPLAY 0.489362 (-6570 1385);
PAINT WHITE (-6570 1385);
FORCEPROP 0 LASTPIN (-6575 1575) XNET_PINS 3
R 1
J 0
(-6585 1585);
DISPLAY 0.808511 (-6585 1585);
PAINT MONO (-6585 1585);
DISPLAY INVISIBLE (-6585 1585);
FORCEPROP 0 LASTPIN (-6575 1375) XNET_PINS 2
R 1
J 2
(-6585 1365);
DISPLAY 0.808511 (-6585 1365);
PAINT MONO (-6585 1365);
DISPLAY INVISIBLE (-6585 1365);
FORCEPROP 1 LAST WATTAGE 1/16W
J 0
(-6535 1450);
DISPLAY 0.489362 (-6535 1450);
PAINT SKYBLUE (-6535 1450);
FORCEPROP 1 LAST MATERIAL CHIP
J 0
(-6535 1400);
DISPLAY 0.489362 (-6535 1400);
PAINT SKYBLUE (-6535 1400);
FORCEPROP 1 LAST TOLERANCE 1%
J 0
(-6530 1500);
DISPLAY 0.489362 (-6530 1500);
PAINT SKYBLUE (-6530 1500);
FORCEPROP 1 LAST VALUE 54.9K
J 0
(-6530 1550);
DISPLAY 0.489362 (-6530 1550);
PAINT SKYBLUE (-6530 1550);
FORCEPROP 1 LAST PART_NUMBER TMP_QCS35492FB14
J 0
(-6535 1350);
DISPLAY 0.489362 (-6535 1350);
PAINT SKYBLUE (-6535 1350);
FORCEPROP 1 LAST PACK_TYPE 0402LF
J 0
(-6535 1300);
DISPLAY 0.489362 (-6535 1300);
PAINT SKYBLUE (-6535 1300);
FORCEPROP 2 LAST BOM_COST MEM
J 0
(-6525 1650);
DISPLAY 0.808511 (-6525 1650);
DISPLAY INVISIBLE (-6525 1650);
FORCEPROP 2 LAST CDS_LIB pure_quanta
J 0
(-6575 1475);
DISPLAY INVISIBLE (-6575 1475);
FORCEPROP 2 LAST SEC_TYPE 0402LF
J 0
(-6525 1700);
DISPLAY 0.808511 (-6525 1700);
PAINT MONO (-6525 1700);
DISPLAY INVISIBLE (-6525 1700);
FORCEPROP 1 LAST PATH I127
J 0
(-6525 1650);
DISPLAY 0.978723 (-6525 1650);
PAINT WHITE (-6525 1650);
DISPLAY INVISIBLE (-6525 1650);
FORCEADD OFFPAGE..5
(-7350 1650);
FORCEPROP 2 LAST $XR0 101 
J 0
(-7605 1650);
DISPLAY 0.638298 (-7605 1650);
PAINT MONO (-7605 1650);
FORCEPROP 2 LAST PATH I128
J 0
(-7600 1700);
DISPLAY 1.021277 (-7600 1700);
DISPLAY INVISIBLE (-7600 1700);
FORCEPROP 1 LAST COMMENT_BODY TRUE
J 0
(-7250 1575);
DISPLAY 0.872340 (-7250 1575);
PAINT GREEN (-7250 1575);
DISPLAY INVISIBLE (-7250 1575);
FORCEPROP 1 LAST OFFPAGE TRUE
J 0
(-7025 1525);
DISPLAY 0.872340 (-7025 1525);
PAINT GREEN (-7025 1525);
DISPLAY INVISIBLE (-7025 1525);
FORCEPROP 2 LAST CDS_LIB mstr_standard
J 0
(-7350 1650);
DISPLAY 0.808511 (-7350 1650);
DISPLAY INVISIBLE (-7350 1650);
FORCEPROP 2 LAST BOM_COST MEM
J 0
(-7425 1725);
DISPLAY 0.808511 (-7425 1725);
DISPLAY INVISIBLE (-7425 1725);
FORCEADD TAP..1
R 2
(-7875 3550);
FORCEPROP 3 LASTPIN (-7825 3550) SIG_NAME M_E_CPU1_SB_CB<2>
J 0
(-7815 3560);
DISPLAY 0.659574 (-7815 3560);
PAINT MONO (-7815 3560);
DISPLAY INVISIBLE (-7815 3560);
FORCEPROP 1 LASTPIN (-7825 3550) BN 2
J 2
(-7813 3558);
DISPLAY 0.489362 (-7813 3558);
PAINT GREEN (-7813 3558);
FORCEPROP 2 LAST CDS_LIB mstr_standard
J 0
(-7875 3550);
DISPLAY 0.723404 (-7875 3550);
PAINT MONO (-7875 3550);
DISPLAY INVISIBLE (-7875 3550);
FORCEPROP 1 LAST BODY_TYPE PLUMBING
J 2
(-7875 3600);
DISPLAY 0.872340 (-7875 3600);
PAINT GREEN (-7875 3600);
DISPLAY INVISIBLE (-7875 3600);
FORCEPROP 1 LAST HDL_TAP TRUE
J 2
(-8200 3425);
DISPLAY 0.872340 (-8200 3425);
DISPLAY INVISIBLE (-8200 3425);
FORCEPROP 1 LAST PATH I13
J 2
(-7873 3550);
DISPLAY 0.872340 (-7873 3550);
PAINT GREEN (-7873 3550);
DISPLAY INVISIBLE (-7873 3550);
FORCEADD TAP..1
R 2
(-7875 3600);
FORCEPROP 3 LASTPIN (-7825 3600) SIG_NAME M_E_CPU1_SB_CB<3>
J 0
(-7815 3610);
DISPLAY 0.659574 (-7815 3610);
PAINT MONO (-7815 3610);
DISPLAY INVISIBLE (-7815 3610);
FORCEPROP 1 LASTPIN (-7825 3600) BN 3
J 2
(-7813 3608);
DISPLAY 0.489362 (-7813 3608);
PAINT GREEN (-7813 3608);
FORCEPROP 2 LAST CDS_LIB mstr_standard
J 0
(-7875 3600);
DISPLAY 0.723404 (-7875 3600);
PAINT MONO (-7875 3600);
DISPLAY INVISIBLE (-7875 3600);
FORCEPROP 1 LAST BODY_TYPE PLUMBING
J 2
(-7875 3650);
DISPLAY 0.872340 (-7875 3650);
PAINT GREEN (-7875 3650);
DISPLAY INVISIBLE (-7875 3650);
FORCEPROP 1 LAST HDL_TAP TRUE
J 2
(-8200 3475);
DISPLAY 0.872340 (-8200 3475);
DISPLAY INVISIBLE (-8200 3475);
FORCEPROP 1 LAST PATH I14
J 2
(-7873 3600);
DISPLAY 0.872340 (-7873 3600);
PAINT GREEN (-7873 3600);
DISPLAY INVISIBLE (-7873 3600);
FORCEADD GND..1
(-2175 2250);
FORCEPROP 3 LASTPIN (-2175 2300) SIG_NAME GND\g
J 0
(-2165 2310);
DISPLAY 0.659574 (-2165 2310);
PAINT MONO (-2165 2310);
DISPLAY INVISIBLE (-2165 2310);
FORCEPROP 2 LAST CDS_LIB mstr_symbols
J 0
(-2175 2250);
DISPLAY 0.723404 (-2175 2250);
DISPLAY INVISIBLE (-2175 2250);
FORCEPROP 1 LAST SIZE 1B
J 0
(-2100 2200);
DISPLAY 0.851064 (-2100 2200);
PAINT GREEN (-2100 2200);
DISPLAY INVISIBLE (-2100 2200);
FORCEPROP 1 LAST BODY_TYPE PLUMBING
J 0
(-2220 2207);
DISPLAY 0.340426 (-2220 2207);
PAINT GREEN (-2220 2207);
DISPLAY INVISIBLE (-2220 2207);
FORCEPROP 1 LAST PATH I140
J 0
(-2100 2250);
DISPLAY 0.872340 (-2100 2250);
PAINT AQUA (-2100 2250);
DISPLAY INVISIBLE (-2100 2250);
FORCEPROP 1 LAST VOLTAGE 0.0
J 0
(-2220 2207);
DISPLAY 0.723404 (-2220 2207);
PAINT SKYBLUE (-2220 2207);
DISPLAY INVISIBLE (-2220 2207);
FORCEPROP 1 LAST HDL_POWER GND
J 0
(-2175 2400);
DISPLAY 0.851064 (-2175 2400);
PAINT GREEN (-2175 2400);
DISPLAY INVISIBLE (-2175 2400);
FORCEADD GND..1
(-375 2075);
FORCEPROP 3 LASTPIN (-375 2125) SIG_NAME GND\g
J 0
(-365 2135);
DISPLAY 0.659574 (-365 2135);
PAINT MONO (-365 2135);
DISPLAY INVISIBLE (-365 2135);
FORCEPROP 2 LAST CDS_LIB mstr_symbols
J 0
(-375 2075);
DISPLAY 0.723404 (-375 2075);
DISPLAY INVISIBLE (-375 2075);
FORCEPROP 1 LAST SIZE 1B
J 0
(-300 2025);
DISPLAY 0.851064 (-300 2025);
PAINT GREEN (-300 2025);
DISPLAY INVISIBLE (-300 2025);
FORCEPROP 1 LAST BODY_TYPE PLUMBING
J 0
(-420 2032);
DISPLAY 0.340426 (-420 2032);
PAINT GREEN (-420 2032);
DISPLAY INVISIBLE (-420 2032);
FORCEPROP 1 LAST PATH I141
J 0
(-300 2075);
DISPLAY 0.872340 (-300 2075);
PAINT AQUA (-300 2075);
DISPLAY INVISIBLE (-300 2075);
FORCEPROP 1 LAST VOLTAGE 0.0
J 0
(-420 2032);
DISPLAY 0.723404 (-420 2032);
PAINT SKYBLUE (-420 2032);
DISPLAY INVISIBLE (-420 2032);
FORCEPROP 1 LAST HDL_POWER GND
J 0
(-375 2225);
DISPLAY 0.851064 (-375 2225);
PAINT GREEN (-375 2225);
DISPLAY INVISIBLE (-375 2225);
FORCEADD TAP..1
R 2
(-7875 3650);
FORCEPROP 3 LASTPIN (-7825 3650) SIG_NAME M_E_CPU1_SB_CB<4>
J 0
(-7815 3660);
DISPLAY 0.659574 (-7815 3660);
PAINT MONO (-7815 3660);
DISPLAY INVISIBLE (-7815 3660);
FORCEPROP 1 LASTPIN (-7825 3650) BN 4
J 2
(-7813 3658);
DISPLAY 0.489362 (-7813 3658);
PAINT GREEN (-7813 3658);
FORCEPROP 2 LAST CDS_LIB mstr_standard
J 0
(-7875 3650);
DISPLAY 0.723404 (-7875 3650);
PAINT MONO (-7875 3650);
DISPLAY INVISIBLE (-7875 3650);
FORCEPROP 1 LAST BODY_TYPE PLUMBING
J 2
(-7875 3700);
DISPLAY 0.872340 (-7875 3700);
PAINT GREEN (-7875 3700);
DISPLAY INVISIBLE (-7875 3700);
FORCEPROP 1 LAST HDL_TAP TRUE
J 2
(-8200 3525);
DISPLAY 0.872340 (-8200 3525);
DISPLAY INVISIBLE (-8200 3525);
FORCEPROP 1 LAST PATH I15
J 2
(-7873 3650);
DISPLAY 0.872340 (-7873 3650);
PAINT GREEN (-7873 3650);
DISPLAY INVISIBLE (-7873 3650);
FORCEADD TAP..1
R 2
(-7875 3700);
FORCEPROP 3 LASTPIN (-7825 3700) SIG_NAME M_E_CPU1_SB_CB<5>
J 0
(-7815 3710);
DISPLAY 0.659574 (-7815 3710);
PAINT MONO (-7815 3710);
DISPLAY INVISIBLE (-7815 3710);
FORCEPROP 1 LASTPIN (-7825 3700) BN 5
J 2
(-7813 3708);
DISPLAY 0.489362 (-7813 3708);
PAINT GREEN (-7813 3708);
FORCEPROP 2 LAST CDS_LIB mstr_standard
J 0
(-7875 3700);
DISPLAY 0.723404 (-7875 3700);
PAINT MONO (-7875 3700);
DISPLAY INVISIBLE (-7875 3700);
FORCEPROP 1 LAST BODY_TYPE PLUMBING
J 2
(-7875 3750);
DISPLAY 0.872340 (-7875 3750);
PAINT GREEN (-7875 3750);
DISPLAY INVISIBLE (-7875 3750);
FORCEPROP 1 LAST HDL_TAP TRUE
J 2
(-8200 3575);
DISPLAY 0.872340 (-8200 3575);
DISPLAY INVISIBLE (-8200 3575);
FORCEPROP 1 LAST PATH I16
J 2
(-7873 3700);
DISPLAY 0.872340 (-7873 3700);
PAINT GREEN (-7873 3700);
DISPLAY INVISIBLE (-7873 3700);
FORCEADD TAP..1
R 2
(-7875 3750);
FORCEPROP 3 LASTPIN (-7825 3750) SIG_NAME M_E_CPU1_SB_CB<6>
J 0
(-7815 3760);
DISPLAY 0.659574 (-7815 3760);
PAINT MONO (-7815 3760);
DISPLAY INVISIBLE (-7815 3760);
FORCEPROP 1 LASTPIN (-7825 3750) BN 6
J 2
(-7813 3758);
DISPLAY 0.489362 (-7813 3758);
PAINT GREEN (-7813 3758);
FORCEPROP 2 LAST CDS_LIB mstr_standard
J 0
(-7875 3750);
DISPLAY 0.723404 (-7875 3750);
PAINT MONO (-7875 3750);
DISPLAY INVISIBLE (-7875 3750);
FORCEPROP 1 LAST BODY_TYPE PLUMBING
J 2
(-7875 3800);
DISPLAY 0.872340 (-7875 3800);
PAINT GREEN (-7875 3800);
DISPLAY INVISIBLE (-7875 3800);
FORCEPROP 1 LAST HDL_TAP TRUE
J 2
(-8200 3625);
DISPLAY 0.872340 (-8200 3625);
DISPLAY INVISIBLE (-8200 3625);
FORCEPROP 1 LAST PATH I17
J 2
(-7873 3750);
DISPLAY 0.872340 (-7873 3750);
PAINT GREEN (-7873 3750);
DISPLAY INVISIBLE (-7873 3750);
FORCEADD SCONN288_DDR506112002KQ..3
(-1275 4000);
FORCEPROP 1 LAST LOCATION J32
J 0
(-1725 5975);
DISPLAY 0.468085 (-1725 5975);
PAINT SKYBLUE (-1725 5975);
FORCEPROP 0 LAST $SEC 3
J 0
(-1725 6125);
DISPLAY 0.680851 (-1725 6125);
PAINT MONO (-1725 6125);
DISPLAY INVISIBLE (-1725 6125);
FORCEPROP 2 LAST CDS_SEC 3
J 0
(-1725 6125);
DISPLAY 1.021277 (-1725 6125);
DISPLAY INVISIBLE (-1725 6125);
FORCEPROP 0 LASTPIN (-675 2400) $PN G1
J 0
(-665 2410);
DISPLAY 0.680851 (-665 2410);
PAINT MONO (-665 2410);
FORCEPROP 0 LASTPIN (-675 2350) $PN G2
J 0
(-665 2360);
DISPLAY 0.680851 (-665 2360);
PAINT MONO (-665 2360);
FORCEPROP 0 LASTPIN (-675 2300) $PN G3
J 0
(-665 2310);
DISPLAY 0.680851 (-665 2310);
PAINT MONO (-665 2310);
FORCEPROP 0 LASTPIN (-1875 5550) $PN 1
J 2
(-1885 5560);
DISPLAY 0.680851 (-1885 5560);
PAINT MONO (-1885 5560);
FORCEPROP 0 LASTPIN (-1875 5600) $PN 145
J 2
(-1885 5610);
DISPLAY 0.680851 (-1885 5610);
PAINT MONO (-1885 5610);
FORCEPROP 0 LASTPIN (-1875 5650) $PN 146
J 2
(-1885 5660);
DISPLAY 0.680851 (-1885 5660);
PAINT MONO (-1885 5660);
FORCEPROP 0 LASTPIN (-675 2500) $PN 6
J 0
(-665 2510);
DISPLAY 0.680851 (-665 2510);
PAINT MONO (-665 2510);
FORCEPROP 0 LASTPIN (-675 2550) $PN 8
J 0
(-665 2560);
DISPLAY 0.680851 (-665 2560);
PAINT MONO (-665 2560);
FORCEPROP 0 LASTPIN (-675 2600) $PN 10
J 0
(-665 2610);
DISPLAY 0.680851 (-665 2610);
PAINT MONO (-665 2610);
FORCEPROP 0 LASTPIN (-675 2650) $PN 13
J 0
(-665 2660);
DISPLAY 0.680851 (-665 2660);
PAINT MONO (-665 2660);
FORCEPROP 0 LASTPIN (-675 2700) $PN 15
J 0
(-665 2710);
DISPLAY 0.680851 (-665 2710);
PAINT MONO (-665 2710);
FORCEPROP 0 LASTPIN (-675 2750) $PN 17
J 0
(-665 2760);
DISPLAY 0.680851 (-665 2760);
PAINT MONO (-665 2760);
FORCEPROP 0 LASTPIN (-675 2800) $PN 19
J 0
(-665 2810);
DISPLAY 0.680851 (-665 2810);
PAINT MONO (-665 2810);
FORCEPROP 0 LASTPIN (-675 2850) $PN 21
J 0
(-665 2860);
DISPLAY 0.680851 (-665 2860);
PAINT MONO (-665 2860);
FORCEPROP 0 LASTPIN (-675 2900) $PN 24
J 0
(-665 2910);
DISPLAY 0.680851 (-665 2910);
PAINT MONO (-665 2910);
FORCEPROP 0 LASTPIN (-675 2950) $PN 26
J 0
(-665 2960);
DISPLAY 0.680851 (-665 2960);
PAINT MONO (-665 2960);
FORCEPROP 0 LASTPIN (-675 3000) $PN 28
J 0
(-665 3010);
DISPLAY 0.680851 (-665 3010);
PAINT MONO (-665 3010);
FORCEPROP 0 LASTPIN (-675 3050) $PN 30
J 0
(-665 3060);
DISPLAY 0.680851 (-665 3060);
PAINT MONO (-665 3060);
FORCEPROP 0 LASTPIN (-675 3100) $PN 32
J 0
(-665 3110);
DISPLAY 0.680851 (-665 3110);
PAINT MONO (-665 3110);
FORCEPROP 0 LASTPIN (-675 3150) $PN 35
J 0
(-665 3160);
DISPLAY 0.680851 (-665 3160);
PAINT MONO (-665 3160);
FORCEPROP 0 LASTPIN (-675 3200) $PN 37
J 0
(-665 3210);
DISPLAY 0.680851 (-665 3210);
PAINT MONO (-665 3210);
FORCEPROP 0 LASTPIN (-675 3250) $PN 39
J 0
(-665 3260);
DISPLAY 0.680851 (-665 3260);
PAINT MONO (-665 3260);
FORCEPROP 0 LASTPIN (-675 3300) $PN 41
J 0
(-665 3310);
DISPLAY 0.680851 (-665 3310);
PAINT MONO (-665 3310);
FORCEPROP 0 LASTPIN (-675 3350) $PN 43
J 0
(-665 3360);
DISPLAY 0.680851 (-665 3360);
PAINT MONO (-665 3360);
FORCEPROP 0 LASTPIN (-675 3400) $PN 46
J 0
(-665 3410);
DISPLAY 0.680851 (-665 3410);
PAINT MONO (-665 3410);
FORCEPROP 0 LASTPIN (-675 3450) $PN 48
J 0
(-665 3460);
DISPLAY 0.680851 (-665 3460);
PAINT MONO (-665 3460);
FORCEPROP 0 LASTPIN (-675 3500) $PN 50
J 0
(-665 3510);
DISPLAY 0.680851 (-665 3510);
PAINT MONO (-665 3510);
FORCEPROP 0 LASTPIN (-675 3550) $PN 52
J 0
(-665 3560);
DISPLAY 0.680851 (-665 3560);
PAINT MONO (-665 3560);
FORCEPROP 0 LASTPIN (-675 3600) $PN 54
J 0
(-665 3610);
DISPLAY 0.680851 (-665 3610);
PAINT MONO (-665 3610);
FORCEPROP 0 LASTPIN (-675 3650) $PN 57
J 0
(-665 3660);
DISPLAY 0.680851 (-665 3660);
PAINT MONO (-665 3660);
FORCEPROP 0 LASTPIN (-675 3700) $PN 59
J 0
(-665 3710);
DISPLAY 0.680851 (-665 3710);
PAINT MONO (-665 3710);
FORCEPROP 0 LASTPIN (-675 3750) $PN 61
J 0
(-665 3760);
DISPLAY 0.680851 (-665 3760);
PAINT MONO (-665 3760);
FORCEPROP 0 LASTPIN (-675 3800) $PN 63
J 0
(-665 3810);
DISPLAY 0.680851 (-665 3810);
PAINT MONO (-665 3810);
FORCEPROP 0 LASTPIN (-675 3850) $PN 65
J 0
(-665 3860);
DISPLAY 0.680851 (-665 3860);
PAINT MONO (-665 3860);
FORCEPROP 0 LASTPIN (-675 3900) $PN 67
J 0
(-665 3910);
DISPLAY 0.680851 (-665 3910);
PAINT MONO (-665 3910);
FORCEPROP 0 LASTPIN (-675 3950) $PN 69
J 0
(-665 3960);
DISPLAY 0.680851 (-665 3960);
PAINT MONO (-665 3960);
FORCEPROP 0 LASTPIN (-675 4000) $PN 71
J 0
(-665 4010);
DISPLAY 0.680851 (-665 4010);
PAINT MONO (-665 4010);
FORCEPROP 0 LASTPIN (-675 4050) $PN 73
J 0
(-665 4060);
DISPLAY 0.680851 (-665 4060);
PAINT MONO (-665 4060);
FORCEPROP 0 LASTPIN (-675 4100) $PN 75
J 0
(-665 4110);
DISPLAY 0.680851 (-665 4110);
PAINT MONO (-665 4110);
FORCEPROP 0 LASTPIN (-675 4150) $PN 77
J 0
(-665 4160);
DISPLAY 0.680851 (-665 4160);
PAINT MONO (-665 4160);
FORCEPROP 0 LASTPIN (-675 4200) $PN 79
J 0
(-665 4210);
DISPLAY 0.680851 (-665 4210);
PAINT MONO (-665 4210);
FORCEPROP 0 LASTPIN (-675 4250) $PN 81
J 0
(-665 4260);
DISPLAY 0.680851 (-665 4260);
PAINT MONO (-665 4260);
FORCEPROP 0 LASTPIN (-675 4300) $PN 83
J 0
(-665 4310);
DISPLAY 0.680851 (-665 4310);
PAINT MONO (-665 4310);
FORCEPROP 0 LASTPIN (-675 4350) $PN 85
J 0
(-665 4360);
DISPLAY 0.680851 (-665 4360);
PAINT MONO (-665 4360);
FORCEPROP 0 LASTPIN (-675 4400) $PN 88
J 0
(-665 4410);
DISPLAY 0.680851 (-665 4410);
PAINT MONO (-665 4410);
FORCEPROP 0 LASTPIN (-675 4450) $PN 90
J 0
(-665 4460);
DISPLAY 0.680851 (-665 4460);
PAINT MONO (-665 4460);
FORCEPROP 0 LASTPIN (-675 4500) $PN 92
J 0
(-665 4510);
DISPLAY 0.680851 (-665 4510);
PAINT MONO (-665 4510);
FORCEPROP 0 LASTPIN (-675 4550) $PN 95
J 0
(-665 4560);
DISPLAY 0.680851 (-665 4560);
PAINT MONO (-665 4560);
FORCEPROP 0 LASTPIN (-675 4600) $PN 97
J 0
(-665 4610);
DISPLAY 0.680851 (-665 4610);
PAINT MONO (-665 4610);
FORCEPROP 0 LASTPIN (-675 4650) $PN 99
J 0
(-665 4660);
DISPLAY 0.680851 (-665 4660);
PAINT MONO (-665 4660);
FORCEPROP 0 LASTPIN (-675 4700) $PN 101
J 0
(-665 4710);
DISPLAY 0.680851 (-665 4710);
PAINT MONO (-665 4710);
FORCEPROP 0 LASTPIN (-675 4750) $PN 103
J 0
(-665 4760);
DISPLAY 0.680851 (-665 4760);
PAINT MONO (-665 4760);
FORCEPROP 0 LASTPIN (-675 4800) $PN 106
J 0
(-665 4810);
DISPLAY 0.680851 (-665 4810);
PAINT MONO (-665 4810);
FORCEPROP 0 LASTPIN (-675 4850) $PN 108
J 0
(-665 4860);
DISPLAY 0.680851 (-665 4860);
PAINT MONO (-665 4860);
FORCEPROP 0 LASTPIN (-675 4900) $PN 110
J 0
(-665 4910);
DISPLAY 0.680851 (-665 4910);
PAINT MONO (-665 4910);
FORCEPROP 0 LASTPIN (-675 4950) $PN 112
J 0
(-665 4960);
DISPLAY 0.680851 (-665 4960);
PAINT MONO (-665 4960);
FORCEPROP 0 LASTPIN (-675 5000) $PN 114
J 0
(-665 5010);
DISPLAY 0.680851 (-665 5010);
PAINT MONO (-665 5010);
FORCEPROP 0 LASTPIN (-675 5050) $PN 117
J 0
(-665 5060);
DISPLAY 0.680851 (-665 5060);
PAINT MONO (-665 5060);
FORCEPROP 0 LASTPIN (-675 5100) $PN 119
J 0
(-665 5110);
DISPLAY 0.680851 (-665 5110);
PAINT MONO (-665 5110);
FORCEPROP 0 LASTPIN (-675 5150) $PN 121
J 0
(-665 5160);
DISPLAY 0.680851 (-665 5160);
PAINT MONO (-665 5160);
FORCEPROP 0 LASTPIN (-675 5200) $PN 123
J 0
(-665 5210);
DISPLAY 0.680851 (-665 5210);
PAINT MONO (-665 5210);
FORCEPROP 0 LASTPIN (-675 5250) $PN 125
J 0
(-665 5260);
DISPLAY 0.680851 (-665 5260);
PAINT MONO (-665 5260);
FORCEPROP 0 LASTPIN (-675 5300) $PN 128
J 0
(-665 5310);
DISPLAY 0.680851 (-665 5310);
PAINT MONO (-665 5310);
FORCEPROP 0 LASTPIN (-675 5350) $PN 130
J 0
(-665 5360);
DISPLAY 0.680851 (-665 5360);
PAINT MONO (-665 5360);
FORCEPROP 0 LASTPIN (-675 5400) $PN 132
J 0
(-665 5410);
DISPLAY 0.680851 (-665 5410);
PAINT MONO (-665 5410);
FORCEPROP 0 LASTPIN (-675 5450) $PN 134
J 0
(-665 5460);
DISPLAY 0.680851 (-665 5460);
PAINT MONO (-665 5460);
FORCEPROP 0 LASTPIN (-675 5500) $PN 136
J 0
(-665 5510);
DISPLAY 0.680851 (-665 5510);
PAINT MONO (-665 5510);
FORCEPROP 0 LASTPIN (-675 5550) $PN 139
J 0
(-665 5560);
DISPLAY 0.680851 (-665 5560);
PAINT MONO (-665 5560);
FORCEPROP 0 LASTPIN (-675 5600) $PN 141
J 0
(-665 5610);
DISPLAY 0.680851 (-665 5610);
PAINT MONO (-665 5610);
FORCEPROP 0 LASTPIN (-675 5650) $PN 143
J 0
(-665 5660);
DISPLAY 0.680851 (-665 5660);
PAINT MONO (-665 5660);
FORCEPROP 0 LASTPIN (-1875 2400) $PN 151
J 2
(-1885 2410);
DISPLAY 0.680851 (-1885 2410);
PAINT MONO (-1885 2410);
FORCEPROP 0 LASTPIN (-1875 2450) $PN 153
J 2
(-1885 2460);
DISPLAY 0.680851 (-1885 2460);
PAINT MONO (-1885 2460);
FORCEPROP 0 LASTPIN (-1875 2500) $PN 155
J 2
(-1885 2510);
DISPLAY 0.680851 (-1885 2510);
PAINT MONO (-1885 2510);
FORCEPROP 0 LASTPIN (-1875 2550) $PN 158
J 2
(-1885 2560);
DISPLAY 0.680851 (-1885 2560);
PAINT MONO (-1885 2560);
FORCEPROP 0 LASTPIN (-1875 2600) $PN 160
J 2
(-1885 2610);
DISPLAY 0.680851 (-1885 2610);
PAINT MONO (-1885 2610);
FORCEPROP 0 LASTPIN (-1875 2650) $PN 162
J 2
(-1885 2660);
DISPLAY 0.680851 (-1885 2660);
PAINT MONO (-1885 2660);
FORCEPROP 0 LASTPIN (-1875 2700) $PN 164
J 2
(-1885 2710);
DISPLAY 0.680851 (-1885 2710);
PAINT MONO (-1885 2710);
FORCEPROP 0 LASTPIN (-1875 2750) $PN 166
J 2
(-1885 2760);
DISPLAY 0.680851 (-1885 2760);
PAINT MONO (-1885 2760);
FORCEPROP 0 LASTPIN (-1875 2800) $PN 169
J 2
(-1885 2810);
DISPLAY 0.680851 (-1885 2810);
PAINT MONO (-1885 2810);
FORCEPROP 0 LASTPIN (-1875 2850) $PN 171
J 2
(-1885 2860);
DISPLAY 0.680851 (-1885 2860);
PAINT MONO (-1885 2860);
FORCEPROP 0 LASTPIN (-1875 2900) $PN 173
J 2
(-1885 2910);
DISPLAY 0.680851 (-1885 2910);
PAINT MONO (-1885 2910);
FORCEPROP 0 LASTPIN (-1875 2950) $PN 175
J 2
(-1885 2960);
DISPLAY 0.680851 (-1885 2960);
PAINT MONO (-1885 2960);
FORCEPROP 0 LASTPIN (-1875 3000) $PN 177
J 2
(-1885 3010);
DISPLAY 0.680851 (-1885 3010);
PAINT MONO (-1885 3010);
FORCEPROP 0 LASTPIN (-1875 3050) $PN 180
J 2
(-1885 3060);
DISPLAY 0.680851 (-1885 3060);
PAINT MONO (-1885 3060);
FORCEPROP 0 LASTPIN (-1875 3100) $PN 182
J 2
(-1885 3110);
DISPLAY 0.680851 (-1885 3110);
PAINT MONO (-1885 3110);
FORCEPROP 0 LASTPIN (-1875 3150) $PN 184
J 2
(-1885 3160);
DISPLAY 0.680851 (-1885 3160);
PAINT MONO (-1885 3160);
FORCEPROP 0 LASTPIN (-1875 3200) $PN 186
J 2
(-1885 3210);
DISPLAY 0.680851 (-1885 3210);
PAINT MONO (-1885 3210);
FORCEPROP 0 LASTPIN (-1875 3250) $PN 188
J 2
(-1885 3260);
DISPLAY 0.680851 (-1885 3260);
PAINT MONO (-1885 3260);
FORCEPROP 0 LASTPIN (-1875 3300) $PN 191
J 2
(-1885 3310);
DISPLAY 0.680851 (-1885 3310);
PAINT MONO (-1885 3310);
FORCEPROP 0 LASTPIN (-1875 3350) $PN 193
J 2
(-1885 3360);
DISPLAY 0.680851 (-1885 3360);
PAINT MONO (-1885 3360);
FORCEPROP 0 LASTPIN (-1875 3400) $PN 195
J 2
(-1885 3410);
DISPLAY 0.680851 (-1885 3410);
PAINT MONO (-1885 3410);
FORCEPROP 0 LASTPIN (-1875 3450) $PN 197
J 2
(-1885 3460);
DISPLAY 0.680851 (-1885 3460);
PAINT MONO (-1885 3460);
FORCEPROP 0 LASTPIN (-1875 3500) $PN 199
J 2
(-1885 3510);
DISPLAY 0.680851 (-1885 3510);
PAINT MONO (-1885 3510);
FORCEPROP 0 LASTPIN (-1875 3550) $PN 202
J 2
(-1885 3560);
DISPLAY 0.680851 (-1885 3560);
PAINT MONO (-1885 3560);
FORCEPROP 0 LASTPIN (-1875 3600) $PN 204
J 2
(-1885 3610);
DISPLAY 0.680851 (-1885 3610);
PAINT MONO (-1885 3610);
FORCEPROP 0 LASTPIN (-1875 3650) $PN 206
J 2
(-1885 3660);
DISPLAY 0.680851 (-1885 3660);
PAINT MONO (-1885 3660);
FORCEPROP 0 LASTPIN (-1875 3700) $PN 208
J 2
(-1885 3710);
DISPLAY 0.680851 (-1885 3710);
PAINT MONO (-1885 3710);
FORCEPROP 0 LASTPIN (-1875 3750) $PN 210
J 2
(-1885 3760);
DISPLAY 0.680851 (-1885 3760);
PAINT MONO (-1885 3760);
FORCEPROP 0 LASTPIN (-1875 3800) $PN 212
J 2
(-1885 3810);
DISPLAY 0.680851 (-1885 3810);
PAINT MONO (-1885 3810);
FORCEPROP 0 LASTPIN (-1875 3850) $PN 214
J 2
(-1885 3860);
DISPLAY 0.680851 (-1885 3860);
PAINT MONO (-1885 3860);
FORCEPROP 0 LASTPIN (-1875 3900) $PN 216
J 2
(-1885 3910);
DISPLAY 0.680851 (-1885 3910);
PAINT MONO (-1885 3910);
FORCEPROP 0 LASTPIN (-1875 3950) $PN 219
J 2
(-1885 3960);
DISPLAY 0.680851 (-1885 3960);
PAINT MONO (-1885 3960);
FORCEPROP 0 LASTPIN (-1875 4000) $PN 222
J 2
(-1885 4010);
DISPLAY 0.680851 (-1885 4010);
PAINT MONO (-1885 4010);
FORCEPROP 0 LASTPIN (-1875 4050) $PN 224
J 2
(-1885 4060);
DISPLAY 0.680851 (-1885 4060);
PAINT MONO (-1885 4060);
FORCEPROP 0 LASTPIN (-1875 4100) $PN 226
J 2
(-1885 4110);
DISPLAY 0.680851 (-1885 4110);
PAINT MONO (-1885 4110);
FORCEPROP 0 LASTPIN (-1875 4150) $PN 228
J 2
(-1885 4160);
DISPLAY 0.680851 (-1885 4160);
PAINT MONO (-1885 4160);
FORCEPROP 0 LASTPIN (-1875 4200) $PN 230
J 2
(-1885 4210);
DISPLAY 0.680851 (-1885 4210);
PAINT MONO (-1885 4210);
FORCEPROP 0 LASTPIN (-1875 4250) $PN 233
J 2
(-1885 4260);
DISPLAY 0.680851 (-1885 4260);
PAINT MONO (-1885 4260);
FORCEPROP 0 LASTPIN (-1875 4300) $PN 235
J 2
(-1885 4310);
DISPLAY 0.680851 (-1885 4310);
PAINT MONO (-1885 4310);
FORCEPROP 0 LASTPIN (-1875 4350) $PN 237
J 2
(-1885 4360);
DISPLAY 0.680851 (-1885 4360);
PAINT MONO (-1885 4360);
FORCEPROP 0 LASTPIN (-1875 4400) $PN 240
J 2
(-1885 4410);
DISPLAY 0.680851 (-1885 4410);
PAINT MONO (-1885 4410);
FORCEPROP 0 LASTPIN (-1875 4450) $PN 242
J 2
(-1885 4460);
DISPLAY 0.680851 (-1885 4460);
PAINT MONO (-1885 4460);
FORCEPROP 0 LASTPIN (-1875 4500) $PN 244
J 2
(-1885 4510);
DISPLAY 0.680851 (-1885 4510);
PAINT MONO (-1885 4510);
FORCEPROP 0 LASTPIN (-1875 4550) $PN 246
J 2
(-1885 4560);
DISPLAY 0.680851 (-1885 4560);
PAINT MONO (-1885 4560);
FORCEPROP 0 LASTPIN (-1875 4600) $PN 248
J 2
(-1885 4610);
DISPLAY 0.680851 (-1885 4610);
PAINT MONO (-1885 4610);
FORCEPROP 0 LASTPIN (-1875 4650) $PN 251
J 2
(-1885 4660);
DISPLAY 0.680851 (-1885 4660);
PAINT MONO (-1885 4660);
FORCEPROP 0 LASTPIN (-1875 4700) $PN 253
J 2
(-1885 4710);
DISPLAY 0.680851 (-1885 4710);
PAINT MONO (-1885 4710);
FORCEPROP 0 LASTPIN (-1875 4750) $PN 255
J 2
(-1885 4760);
DISPLAY 0.680851 (-1885 4760);
PAINT MONO (-1885 4760);
FORCEPROP 0 LASTPIN (-1875 4800) $PN 257
J 2
(-1885 4810);
DISPLAY 0.680851 (-1885 4810);
PAINT MONO (-1885 4810);
FORCEPROP 0 LASTPIN (-1875 4850) $PN 259
J 2
(-1885 4860);
DISPLAY 0.680851 (-1885 4860);
PAINT MONO (-1885 4860);
FORCEPROP 0 LASTPIN (-1875 4900) $PN 262
J 2
(-1885 4910);
DISPLAY 0.680851 (-1885 4910);
PAINT MONO (-1885 4910);
FORCEPROP 0 LASTPIN (-1875 4950) $PN 264
J 2
(-1885 4960);
DISPLAY 0.680851 (-1885 4960);
PAINT MONO (-1885 4960);
FORCEPROP 0 LASTPIN (-1875 5000) $PN 266
J 2
(-1885 5010);
DISPLAY 0.680851 (-1885 5010);
PAINT MONO (-1885 5010);
FORCEPROP 0 LASTPIN (-1875 5050) $PN 268
J 2
(-1885 5060);
DISPLAY 0.680851 (-1885 5060);
PAINT MONO (-1885 5060);
FORCEPROP 0 LASTPIN (-1875 5100) $PN 270
J 2
(-1885 5110);
DISPLAY 0.680851 (-1885 5110);
PAINT MONO (-1885 5110);
FORCEPROP 0 LASTPIN (-1875 5150) $PN 273
J 2
(-1885 5160);
DISPLAY 0.680851 (-1885 5160);
PAINT MONO (-1885 5160);
FORCEPROP 0 LASTPIN (-1875 5200) $PN 275
J 2
(-1885 5210);
DISPLAY 0.680851 (-1885 5210);
PAINT MONO (-1885 5210);
FORCEPROP 0 LASTPIN (-1875 5250) $PN 277
J 2
(-1885 5260);
DISPLAY 0.680851 (-1885 5260);
PAINT MONO (-1885 5260);
FORCEPROP 0 LASTPIN (-1875 5300) $PN 279
J 2
(-1885 5310);
DISPLAY 0.680851 (-1885 5310);
PAINT MONO (-1885 5310);
FORCEPROP 0 LASTPIN (-1875 5350) $PN 281
J 2
(-1885 5360);
DISPLAY 0.680851 (-1885 5360);
PAINT MONO (-1885 5360);
FORCEPROP 0 LASTPIN (-1875 5400) $PN 284
J 2
(-1885 5410);
DISPLAY 0.680851 (-1885 5410);
PAINT MONO (-1885 5410);
FORCEPROP 0 LASTPIN (-1875 5450) $PN 286
J 2
(-1885 5460);
DISPLAY 0.680851 (-1885 5460);
PAINT MONO (-1885 5460);
FORCEPROP 0 LASTPIN (-1875 5500) $PN 288
J 2
(-1885 5510);
DISPLAY 0.680851 (-1885 5510);
PAINT MONO (-1885 5510);
FORCEPROP 2 LAST PART_TYPE SMLF
J 0
(-1725 6075);
DISPLAY 1.021277 (-1725 6075);
FORCEPROP 1 LAST MATERIAL IO
J 0
(-1725 5825);
DISPLAY 0.468085 (-1725 5825);
PAINT SKYBLUE (-1725 5825);
FORCEPROP 2 LAST VALUE SCONN288_DDR506112002KQ
J 0
(-1725 6025);
DISPLAY 0.489362 (-1725 6025);
PAINT SKYBLUE (-1725 6025);
FORCEPROP 1 LAST PART_NUMBER DFHST8FS479
J 0
(-1725 5900);
DISPLAY 0.468085 (-1725 5900);
PAINT SKYBLUE (-1725 5900);
FORCEPROP 1 LAST CDS_LMAN_SYM_OUTLINE -450,1800,450,-1750
J 0
(-1275 4000);
DISPLAY 0.468085 (-1275 4000);
PAINT GREEN (-1275 4000);
DISPLAY INVISIBLE (-1275 4000);
FORCEPROP 1 LAST PATH I175
J 0
(-1275 4000);
DISPLAY 0.723404 (-1275 4000);
PAINT GREEN (-1275 4000);
DISPLAY INVISIBLE (-1275 4000);
FORCEPROP 1 LAST NEEDS_NO_SIZE TRUE
J 0
(-1275 4000);
DISPLAY 0.723404 (-1275 4000);
PAINT GREEN (-1275 4000);
DISPLAY INVISIBLE (-1275 4000);
FORCEPROP 2 LAST CDS_LIB pure_quanta
J 0
(-1275 4000);
DISPLAY INVISIBLE (-1275 4000);
FORCEADD OFFPAGE..6
(-8475 3100);
FORCEPROP 2 LAST $XR5 136 
J 0
(-9294 3100);
DISPLAY 0.638298 (-9294 3100);
PAINT MONO (-9294 3100);
FORCEPROP 2 LAST $XR4 102 
J 0
(-9174 3100);
DISPLAY 0.638298 (-9174 3100);
PAINT MONO (-9174 3100);
FORCEPROP 2 LAST $XR3 100 
J 0
(-9054 3100);
DISPLAY 0.638298 (-9054 3100);
PAINT MONO (-9054 3100);
FORCEPROP 2 LAST $XR2 99 
J 0
(-8934 3100);
DISPLAY 0.638298 (-8934 3100);
PAINT MONO (-8934 3100);
FORCEPROP 2 LAST $XR1 98 
J 0
(-8844 3100);
DISPLAY 0.638298 (-8844 3100);
PAINT MONO (-8844 3100);
FORCEPROP 2 LAST $XR0 97 
J 0
(-8754 3100);
DISPLAY 0.638298 (-8754 3100);
PAINT MONO (-8754 3100);
FORCEPROP 2 LAST PATH I179
J 0
(-8750 3150);
DISPLAY 1.021277 (-8750 3150);
DISPLAY INVISIBLE (-8750 3150);
FORCEPROP 1 LAST COMMENT_BODY TRUE
J 0
(-8375 3025);
DISPLAY 0.872340 (-8375 3025);
PAINT GREEN (-8375 3025);
DISPLAY INVISIBLE (-8375 3025);
FORCEPROP 1 LAST OFFPAGE TRUE
J 0
(-8150 2975);
DISPLAY 0.872340 (-8150 2975);
PAINT GREEN (-8150 2975);
DISPLAY INVISIBLE (-8150 2975);
FORCEPROP 2 LAST CDS_LIB mstr_standard
J 0
(-8475 3100);
DISPLAY 0.808511 (-8475 3100);
DISPLAY INVISIBLE (-8475 3100);
FORCEADD TAP..1
R 2
(-7875 3900);
FORCEPROP 3 LASTPIN (-7825 3900) SIG_NAME M_E_CPU1_SA_CB<0>
J 0
(-7815 3910);
DISPLAY 0.659574 (-7815 3910);
PAINT MONO (-7815 3910);
DISPLAY INVISIBLE (-7815 3910);
FORCEPROP 1 LASTPIN (-7825 3900) BN 0
J 2
(-7813 3908);
DISPLAY 0.489362 (-7813 3908);
PAINT GREEN (-7813 3908);
FORCEPROP 2 LAST CDS_LIB mstr_standard
J 0
(-7875 3900);
DISPLAY 0.723404 (-7875 3900);
PAINT MONO (-7875 3900);
DISPLAY INVISIBLE (-7875 3900);
FORCEPROP 1 LAST BODY_TYPE PLUMBING
J 2
(-7875 3950);
DISPLAY 0.872340 (-7875 3950);
PAINT GREEN (-7875 3950);
DISPLAY INVISIBLE (-7875 3950);
FORCEPROP 1 LAST HDL_TAP TRUE
J 2
(-8200 3775);
DISPLAY 0.872340 (-8200 3775);
DISPLAY INVISIBLE (-8200 3775);
FORCEPROP 1 LAST PATH I18
J 2
(-7873 3900);
DISPLAY 0.872340 (-7873 3900);
PAINT GREEN (-7873 3900);
DISPLAY INVISIBLE (-7873 3900);
FORCEADD Q_CAP..1
R 2
(-8800 3475);
FORCEPROP 1 LAST LOCATION C152
J 2
(-8850 3575);
DISPLAY 0.489362 (-8850 3575);
PAINT SKYBLUE (-8850 3575);
FORCEPROP 0 LAST $SEC 1
J 0
(-8850 3625);
DISPLAY 0.680851 (-8850 3625);
PAINT MONO (-8850 3625);
DISPLAY INVISIBLE (-8850 3625);
FORCEPROP 0 LAST CDS_SEC 1
J 0
(-8850 3625);
DISPLAY 1.021277 (-8850 3625);
DISPLAY INVISIBLE (-8850 3625);
FORCEPROP 1 LASTPIN (-8800 3575) $PN 1
J 2
(-8810 3555);
DISPLAY 0.489362 (-8810 3555);
PAINT MONO (-8810 3555);
FORCEPROP 1 LASTPIN (-8800 3375) $PN 2
J 2
(-8810 3355);
DISPLAY 0.489362 (-8810 3355);
PAINT MONO (-8810 3355);
FORCEPROP 1 LAST MATERIAL X7R
J 2
(-8850 3375);
DISPLAY 0.489362 (-8850 3375);
PAINT SKYBLUE (-8850 3375);
FORCEPROP 1 LAST TOLERANCE 10%
J 2
(-8850 3425);
DISPLAY 0.489362 (-8850 3425);
PAINT SKYBLUE (-8850 3425);
FORCEPROP 1 LAST VOLTAGE 25V
J 2
(-8850 3475);
DISPLAY 0.489362 (-8850 3475);
PAINT SKYBLUE (-8850 3475);
FORCEPROP 1 LAST VALUE 0.1UF
J 2
(-8850 3525);
DISPLAY 0.489362 (-8850 3525);
PAINT SKYBLUE (-8850 3525);
FORCEPROP 1 LAST PACK_TYPE 0402
J 2
(-8850 3275);
DISPLAY 0.489362 (-8850 3275);
PAINT SKYBLUE (-8850 3275);
FORCEPROP 1 LAST PART_NUMBER CH4104K1B00
J 2
(-8850 3325);
DISPLAY 0.489362 (-8850 3325);
PAINT SKYBLUE (-8850 3325);
FORCEPROP 2 LAST CDS_LIB pure_quanta
J 0
(-8800 3475);
DISPLAY INVISIBLE (-8800 3475);
FORCEPROP 0 LAST BOM_COST MEM
J 2
(-8855 3620);
DISPLAY 0.595745 (-8855 3620);
PAINT MONO (-8855 3620);
DISPLAY INVISIBLE (-8855 3620);
FORCEPROP 1 LAST PATH I185
J 2
(-8850 3625);
DISPLAY 0.978723 (-8850 3625);
PAINT WHITE (-8850 3625);
DISPLAY INVISIBLE (-8850 3625);
FORCEPROP 0 LAST ROOM MEM_CH_A_CPU0_DIMM1
J 2
(-8855 3620);
DISPLAY 0.595745 (-8855 3620);
PAINT RED (-8855 3620);
DISPLAY INVISIBLE (-8855 3620);
FORCEADD GND..1
(-8800 3250);
FORCEPROP 3 LASTPIN (-8800 3300) SIG_NAME GND\g
J 0
(-8790 3310);
DISPLAY 0.659574 (-8790 3310);
PAINT MONO (-8790 3310);
DISPLAY INVISIBLE (-8790 3310);
FORCEPROP 2 LAST CDS_LIB mstr_symbols
J 0
(-8800 3250);
DISPLAY 0.808511 (-8800 3250);
DISPLAY INVISIBLE (-8800 3250);
FORCEPROP 1 LAST SIZE 1B
J 0
(-8725 3200);
DISPLAY 0.723404 (-8725 3200);
PAINT GREEN (-8725 3200);
DISPLAY INVISIBLE (-8725 3200);
FORCEPROP 2 LAST BOM_COST MEM
J 0
(-8775 3375);
DISPLAY 0.659574 (-8775 3375);
DISPLAY INVISIBLE (-8775 3375);
FORCEPROP 1 LAST BODY_TYPE PLUMBING
J 0
(-8845 3207);
DISPLAY 0.276596 (-8845 3207);
PAINT GREEN (-8845 3207);
DISPLAY INVISIBLE (-8845 3207);
FORCEPROP 1 LAST PATH I186
J 0
(-8725 3250);
DISPLAY 0.872340 (-8725 3250);
PAINT AQUA (-8725 3250);
DISPLAY INVISIBLE (-8725 3250);
FORCEPROP 1 LAST VOLTAGE 0
J 0
(-8820 3345);
DISPLAY 0.829787 (-8820 3345);
PAINT SKYBLUE (-8820 3345);
DISPLAY INVISIBLE (-8820 3345);
FORCEPROP 2 LAST ROOM MEM_EFGH_DECOUPLING_CAPS
J 0
(-8775 3325);
DISPLAY 0.659574 (-8775 3325);
PAINT RED (-8775 3325);
DISPLAY INVISIBLE (-8775 3325);
FORCEPROP 1 LAST HDL_POWER GND
J 0
(-8800 3400);
DISPLAY 0.723404 (-8800 3400);
PAINT GREEN (-8800 3400);
DISPLAY INVISIBLE (-8800 3400);
FORCEADD OFFPAGE..6
(-9125 2400);
FORCEPROP 2 LAST $XR5 81 
J 0
(-9374 2292);
DISPLAY 0.638298 (-9374 2292);
PAINT MONO (-9374 2292);
FORCEPROP 2 LAST $XR4 102 
J 0
(-9374 2472);
DISPLAY 0.638298 (-9374 2472);
PAINT MONO (-9374 2472);
FORCEPROP 2 LAST $XR3 100 
J 0
(-9374 2328);
DISPLAY 0.638298 (-9374 2328);
PAINT MONO (-9374 2328);
FORCEPROP 2 LAST $XR2 99 
J 0
(-9374 2436);
DISPLAY 0.638298 (-9374 2436);
PAINT MONO (-9374 2436);
FORCEPROP 2 LAST $XR1 98 
J 0
(-9374 2364);
DISPLAY 0.638298 (-9374 2364);
PAINT MONO (-9374 2364);
FORCEPROP 2 LAST $XR0 97 
J 0
(-9374 2400);
DISPLAY 0.638298 (-9374 2400);
PAINT MONO (-9374 2400);
FORCEPROP 2 LAST PATH I187
J 0
(-9075 2475);
DISPLAY 1.021277 (-9075 2475);
DISPLAY INVISIBLE (-9075 2475);
FORCEPROP 1 LAST COMMENT_BODY TRUE
J 0
(-9025 2325);
DISPLAY 0.872340 (-9025 2325);
PAINT GREEN (-9025 2325);
DISPLAY INVISIBLE (-9025 2325);
FORCEPROP 1 LAST OFFPAGE TRUE
J 0
(-8800 2275);
DISPLAY 0.872340 (-8800 2275);
PAINT GREEN (-8800 2275);
DISPLAY INVISIBLE (-8800 2275);
FORCEPROP 2 LAST CDS_LIB mstr_standard
J 0
(-9125 2400);
DISPLAY 0.808511 (-9125 2400);
DISPLAY INVISIBLE (-9125 2400);
FORCEADD Q_RES..1
R 2
(-8625 2400);
FORCEPROP 1 LAST LOCATION R307
J 2
(-8600 2425);
DISPLAY 0.489362 (-8600 2425);
PAINT SKYBLUE (-8600 2425);
FORCEPROP 0 LAST $SEC 1
J 0
(-8600 2475);
DISPLAY 0.680851 (-8600 2475);
PAINT MONO (-8600 2475);
DISPLAY INVISIBLE (-8600 2475);
FORCEPROP 0 LAST CDS_SEC 1
J 0
(-8600 2475);
DISPLAY 1.021277 (-8600 2475);
DISPLAY INVISIBLE (-8600 2475);
FORCEPROP 1 LASTPIN (-8525 2400) $PN 1
J 2
(-8537 2412);
DISPLAY 0.489362 (-8537 2412);
PAINT MONO (-8537 2412);
FORCEPROP 1 LASTPIN (-8725 2400) $PN 2
J 2
(-8687 2412);
DISPLAY 0.489362 (-8687 2412);
PAINT MONO (-8687 2412);
FORCEPROP 1 LAST VALUE 0
J 0
(-8625 2350);
DISPLAY 0.489362 (-8625 2350);
PAINT SKYBLUE (-8625 2350);
FORCEPROP 2 LAST CDS_LIB pure_quanta
J 0
(-8625 2400);
DISPLAY INVISIBLE (-8625 2400);
FORCEPROP 2 LAST BOM_COST MEM
J 0
(-8650 2550);
DISPLAY 0.744681 (-8650 2550);
PAINT WHITE (-8650 2550);
DISPLAY INVISIBLE (-8650 2550);
FORCEPROP 1 LAST PATH I188
J 2
(-8575 2550);
DISPLAY 0.978723 (-8575 2550);
PAINT WHITE (-8575 2550);
DISPLAY INVISIBLE (-8575 2550);
FORCEPROP 1 LAST WATTAGE 1/16W
J 0
(-8550 2325);
DISPLAY 0.489362 (-8550 2325);
PAINT SKYBLUE (-8550 2325);
DISPLAY INVISIBLE (-8550 2325);
FORCEPROP 1 LAST MATERIAL CHIP
J 0
(-8800 2375);
DISPLAY 0.489362 (-8800 2375);
PAINT SKYBLUE (-8800 2375);
DISPLAY INVISIBLE (-8800 2375);
FORCEPROP 1 LAST TOLERANCE 5%
J 2
(-8500 2375);
DISPLAY 0.489362 (-8500 2375);
PAINT SKYBLUE (-8500 2375);
DISPLAY INVISIBLE (-8500 2375);
FORCEPROP 1 LAST PART_NUMBER CS00002JB38
J 0
(-8725 2450);
DISPLAY 0.489362 (-8725 2450);
PAINT SKYBLUE (-8725 2450);
DISPLAY INVISIBLE (-8725 2450);
FORCEPROP 1 LAST PACK_TYPE 0402LF
J 0
(-8800 2325);
DISPLAY 0.489362 (-8800 2325);
PAINT SKYBLUE (-8800 2325);
DISPLAY INVISIBLE (-8800 2325);
FORCEPROP 2 LAST ROOM RST_CPU0_PLD_TO_DIMM
J 0
(-8650 2500);
DISPLAY 0.744681 (-8650 2500);
PAINT RED (-8650 2500);
DISPLAY INVISIBLE (-8650 2500);
FORCEADD VCC_CORE..1
(-8500 2725);
FORCEPROP 3 LASTPIN (-8500 2675) SIG_NAME P3V3_STBY\g
J 0
(-8490 2685);
DISPLAY 0.659574 (-8490 2685);
PAINT MONO (-8490 2685);
DISPLAY INVISIBLE (-8490 2685);
FORCEPROP 1 LAST HDL_POWER P3V3_STBY
J 1
(-8500 2775);
DISPLAY 0.489362 (-8500 2775);
PAINT GREEN (-8500 2775);
FORCEPROP 2 LAST CDS_LIB mstr_symbols
J 0
(-8500 2725);
DISPLAY INVISIBLE (-8500 2725);
FORCEPROP 1 LAST PATH I189
J 0
(-8450 2750);
DISPLAY 0.872340 (-8450 2750);
PAINT AQUA (-8450 2750);
DISPLAY INVISIBLE (-8450 2750);
FORCEPROP 0 LAST VOLTAGE 3.3
J 0
(-8775 2875);
DISPLAY 1.021277 (-8775 2875);
PAINT SKYBLUE (-8775 2875);
DISPLAY INVISIBLE (-8775 2875);
FORCEPROP 2 LAST ROOM PVCCINFAON_CPU0_CTRL
J 0
(-8500 2825);
DISPLAY 0.808511 (-8500 2825);
PAINT RED (-8500 2825);
DISPLAY INVISIBLE (-8500 2825);
FORCEADD TAP..1
R 2
(-7875 3800);
FORCEPROP 3 LASTPIN (-7825 3800) SIG_NAME M_E_CPU1_SB_CB<7>
J 0
(-7815 3810);
DISPLAY 0.659574 (-7815 3810);
PAINT MONO (-7815 3810);
DISPLAY INVISIBLE (-7815 3810);
FORCEPROP 1 LASTPIN (-7825 3800) BN 7
J 2
(-7813 3808);
DISPLAY 0.489362 (-7813 3808);
PAINT GREEN (-7813 3808);
FORCEPROP 2 LAST CDS_LIB mstr_standard
J 0
(-7875 3800);
DISPLAY 0.723404 (-7875 3800);
PAINT MONO (-7875 3800);
DISPLAY INVISIBLE (-7875 3800);
FORCEPROP 1 LAST BODY_TYPE PLUMBING
J 2
(-7875 3850);
DISPLAY 0.872340 (-7875 3850);
PAINT GREEN (-7875 3850);
DISPLAY INVISIBLE (-7875 3850);
FORCEPROP 1 LAST HDL_TAP TRUE
J 2
(-8200 3675);
DISPLAY 0.872340 (-8200 3675);
DISPLAY INVISIBLE (-8200 3675);
FORCEPROP 1 LAST PATH I19
J 2
(-7873 3800);
DISPLAY 0.872340 (-7873 3800);
PAINT GREEN (-7873 3800);
DISPLAY INVISIBLE (-7873 3800);
FORCEADD Q_RES..2
(-8500 2550);
FORCEPROP 1 LAST LOCATION R107
J 0
(-8455 2675);
DISPLAY 0.489362 (-8455 2675);
PAINT SKYBLUE (-8455 2675);
FORCEPROP 0 LAST $SEC 1
J 0
(-8450 2725);
DISPLAY 0.680851 (-8450 2725);
PAINT MONO (-8450 2725);
DISPLAY INVISIBLE (-8450 2725);
FORCEPROP 0 LAST CDS_SEC 1
J 0
(-8450 2725);
DISPLAY 1.021277 (-8450 2725);
DISPLAY INVISIBLE (-8450 2725);
FORCEPROP 1 LASTPIN (-8500 2650) $PN 1
J 0
(-8495 2612);
DISPLAY 0.489362 (-8495 2612);
PAINT MONO (-8495 2612);
FORCEPROP 1 LASTPIN (-8500 2450) $PN 2
J 0
(-8495 2460);
DISPLAY 0.489362 (-8495 2460);
PAINT MONO (-8495 2460);
FORCEPROP 1 LAST WATTAGE 1/16W
J 0
(-8450 2575);
DISPLAY 0.489362 (-8450 2575);
PAINT SKYBLUE (-8450 2575);
FORCEPROP 1 LAST MATERIAL EMPTY
J 0
(-8450 2550);
DISPLAY 0.489362 (-8450 2550);
PAINT RED (-8450 2550);
FORCEPROP 1 LAST TOLERANCE 5%
J 0
(-8450 2600);
DISPLAY 0.489362 (-8450 2600);
PAINT SKYBLUE (-8450 2600);
FORCEPROP 1 LAST VALUE 1K
J 0
(-8455 2625);
DISPLAY 0.489362 (-8455 2625);
PAINT SKYBLUE (-8455 2625);
FORCEPROP 1 LAST PACK_TYPE 0402LF
J 0
(-8450 2500);
DISPLAY 0.489362 (-8450 2500);
PAINT SKYBLUE (-8450 2500);
FORCEPROP 2 LAST BOM_COST MEM
J 0
(-8450 2725);
DISPLAY 0.808511 (-8450 2725);
DISPLAY INVISIBLE (-8450 2725);
FORCEPROP 2 LAST CDS_LIB pure_quanta
J 2
(-8500 2550);
DISPLAY INVISIBLE (-8500 2550);
FORCEPROP 1 LAST PATH I190
J 0
(-8450 2725);
DISPLAY 0.978723 (-8450 2725);
PAINT WHITE (-8450 2725);
DISPLAY INVISIBLE (-8450 2725);
FORCEPROP 1 LAST PART_NUMBER TMP_QCS21002JB34
J 0
(-8450 2525);
DISPLAY 0.489362 (-8450 2525);
PAINT SKYBLUE (-8450 2525);
DISPLAY INVISIBLE (-8450 2525);
FORCEPROP 2 LAST ROOM MEM_CH_A_CPU0_DIMM1
J 0
(-8450 2775);
DISPLAY 0.808511 (-8450 2775);
PAINT RED (-8450 2775);
DISPLAY INVISIBLE (-8450 2775);
FORCEADD TAP..1
(-3475 3875);
FORCEPROP 3 LASTPIN (-3525 3875) SIG_NAME M_E_CPU1_SA_DQS_DP<0>
J 0
(-3515 3885);
DISPLAY 0.659574 (-3515 3885);
PAINT MONO (-3515 3885);
DISPLAY INVISIBLE (-3515 3885);
FORCEPROP 1 LASTPIN (-3525 3875) BN 0
J 0
(-3537 3883);
DISPLAY 0.489362 (-3537 3883);
PAINT GREEN (-3537 3883);
FORCEPROP 2 LAST CDS_LIB mstr_standard
J 0
(-3475 3875);
DISPLAY 0.723404 (-3475 3875);
PAINT MONO (-3475 3875);
DISPLAY INVISIBLE (-3475 3875);
FORCEPROP 1 LAST BODY_TYPE PLUMBING
J 0
(-3475 3925);
DISPLAY 0.872340 (-3475 3925);
PAINT GREEN (-3475 3925);
DISPLAY INVISIBLE (-3475 3925);
FORCEPROP 1 LAST HDL_TAP TRUE
J 0
(-3150 3750);
DISPLAY 0.872340 (-3150 3750);
DISPLAY INVISIBLE (-3150 3750);
FORCEPROP 1 LAST PATH I192
J 0
(-3477 3875);
DISPLAY 0.872340 (-3477 3875);
PAINT GREEN (-3477 3875);
DISPLAY INVISIBLE (-3477 3875);
FORCEADD TAP..1
(-3275 4025);
FORCEPROP 3 LASTPIN (-3325 4025) SIG_NAME M_E_CPU1_SA_DQS_DN<2>
J 0
(-3315 4035);
DISPLAY 0.659574 (-3315 4035);
PAINT MONO (-3315 4035);
DISPLAY INVISIBLE (-3315 4035);
FORCEPROP 1 LASTPIN (-3325 4025) BN 2
J 0
(-3337 4033);
DISPLAY 0.489362 (-3337 4033);
PAINT GREEN (-3337 4033);
FORCEPROP 2 LAST CDS_LIB mstr_standard
J 0
(-3275 4025);
DISPLAY 0.723404 (-3275 4025);
PAINT MONO (-3275 4025);
DISPLAY INVISIBLE (-3275 4025);
FORCEPROP 1 LAST BODY_TYPE PLUMBING
J 0
(-3275 4075);
DISPLAY 0.872340 (-3275 4075);
PAINT GREEN (-3275 4075);
DISPLAY INVISIBLE (-3275 4075);
FORCEPROP 1 LAST HDL_TAP TRUE
J 0
(-2950 3900);
DISPLAY 0.872340 (-2950 3900);
DISPLAY INVISIBLE (-2950 3900);
FORCEPROP 1 LAST PATH I193
J 0
(-3277 4025);
DISPLAY 0.872340 (-3277 4025);
PAINT GREEN (-3277 4025);
DISPLAY INVISIBLE (-3277 4025);
FORCEADD OFFPAGE..2
(-2475 4825);
FORCEPROP 2 LAST $XR0 41 
J 0
(-2286 4825);
DISPLAY 0.638298 (-2286 4825);
PAINT MONO (-2286 4825);
FORCEPROP 1 LAST COMMENT_BODY TRUE
J 0
(-2520 4730);
DISPLAY 0.872340 (-2520 4730);
PAINT GREEN (-2520 4730);
DISPLAY INVISIBLE (-2520 4730);
FORCEPROP 1 LAST OFFPAGE TRUE
J 0
(-2150 4700);
DISPLAY 0.723404 (-2150 4700);
PAINT GREEN (-2150 4700);
DISPLAY INVISIBLE (-2150 4700);
FORCEPROP 2 LAST CDS_LIB mstr_standard
J 0
(-2475 4825);
DISPLAY 0.723404 (-2475 4825);
PAINT MONO (-2475 4825);
DISPLAY INVISIBLE (-2475 4825);
FORCEPROP 2 LAST PATH I194
J 0
(-2275 4875);
DISPLAY 0.680851 (-2275 4875);
DISPLAY INVISIBLE (-2275 4875);
FORCEADD OFFPAGE..2
(-2475 4775);
FORCEPROP 2 LAST $XR0 41 
J 0
(-2286 4775);
DISPLAY 0.638298 (-2286 4775);
PAINT MONO (-2286 4775);
FORCEPROP 1 LAST COMMENT_BODY TRUE
J 0
(-2520 4680);
DISPLAY 0.872340 (-2520 4680);
PAINT GREEN (-2520 4680);
DISPLAY INVISIBLE (-2520 4680);
FORCEPROP 1 LAST OFFPAGE TRUE
J 0
(-2150 4650);
DISPLAY 0.723404 (-2150 4650);
PAINT GREEN (-2150 4650);
DISPLAY INVISIBLE (-2150 4650);
FORCEPROP 2 LAST CDS_LIB mstr_standard
J 0
(-2475 4775);
DISPLAY 0.723404 (-2475 4775);
PAINT MONO (-2475 4775);
DISPLAY INVISIBLE (-2475 4775);
FORCEPROP 2 LAST PATH I195
J 0
(-2275 4825);
DISPLAY 0.680851 (-2275 4825);
DISPLAY INVISIBLE (-2275 4825);
FORCEADD OFFPAGE..2
(-2475 3775);
FORCEPROP 2 LAST $XR0 41 
J 0
(-2286 3775);
DISPLAY 0.638298 (-2286 3775);
PAINT MONO (-2286 3775);
FORCEPROP 1 LAST COMMENT_BODY TRUE
J 0
(-2520 3680);
DISPLAY 0.872340 (-2520 3680);
PAINT GREEN (-2520 3680);
DISPLAY INVISIBLE (-2520 3680);
FORCEPROP 1 LAST OFFPAGE TRUE
J 0
(-2150 3650);
DISPLAY 0.723404 (-2150 3650);
PAINT GREEN (-2150 3650);
DISPLAY INVISIBLE (-2150 3650);
FORCEPROP 2 LAST CDS_LIB mstr_standard
J 0
(-2475 3775);
DISPLAY 0.723404 (-2475 3775);
PAINT MONO (-2475 3775);
DISPLAY INVISIBLE (-2475 3775);
FORCEPROP 2 LAST PATH I196
J 0
(-2275 3825);
DISPLAY 0.680851 (-2275 3825);
DISPLAY INVISIBLE (-2275 3825);
FORCEADD OFFPAGE..2
(-2475 3725);
FORCEPROP 2 LAST $XR0 41 
J 0
(-2286 3725);
DISPLAY 0.638298 (-2286 3725);
PAINT MONO (-2286 3725);
FORCEPROP 1 LAST COMMENT_BODY TRUE
J 0
(-2520 3630);
DISPLAY 0.872340 (-2520 3630);
PAINT GREEN (-2520 3630);
DISPLAY INVISIBLE (-2520 3630);
FORCEPROP 1 LAST OFFPAGE TRUE
J 0
(-2150 3600);
DISPLAY 0.723404 (-2150 3600);
PAINT GREEN (-2150 3600);
DISPLAY INVISIBLE (-2150 3600);
FORCEPROP 2 LAST CDS_LIB mstr_standard
J 0
(-2475 3725);
DISPLAY 0.723404 (-2475 3725);
PAINT MONO (-2475 3725);
DISPLAY INVISIBLE (-2475 3725);
FORCEPROP 2 LAST PATH I197
J 0
(-2275 3775);
DISPLAY 0.680851 (-2275 3775);
DISPLAY INVISIBLE (-2275 3775);
FORCEADD TAP..1
(-3275 4625);
FORCEPROP 3 LASTPIN (-3325 4625) SIG_NAME M_E_CPU1_SA_DQS_DN<8>
J 0
(-3315 4635);
DISPLAY 0.659574 (-3315 4635);
PAINT MONO (-3315 4635);
DISPLAY INVISIBLE (-3315 4635);
FORCEPROP 1 LASTPIN (-3325 4625) BN 8
J 0
(-3337 4633);
DISPLAY 0.489362 (-3337 4633);
PAINT GREEN (-3337 4633);
FORCEPROP 2 LAST CDS_LIB mstr_standard
J 0
(-3275 4625);
DISPLAY 0.723404 (-3275 4625);
PAINT MONO (-3275 4625);
DISPLAY INVISIBLE (-3275 4625);
FORCEPROP 1 LAST BODY_TYPE PLUMBING
J 0
(-3275 4675);
DISPLAY 0.872340 (-3275 4675);
PAINT GREEN (-3275 4675);
DISPLAY INVISIBLE (-3275 4675);
FORCEPROP 1 LAST HDL_TAP TRUE
J 0
(-2950 4500);
DISPLAY 0.872340 (-2950 4500);
DISPLAY INVISIBLE (-2950 4500);
FORCEPROP 1 LAST PATH I198
J 0
(-3277 4625);
DISPLAY 0.872340 (-3277 4625);
PAINT GREEN (-3277 4625);
DISPLAY INVISIBLE (-3277 4625);
FORCEADD TAP..1
(-3275 4725);
FORCEPROP 3 LASTPIN (-3325 4725) SIG_NAME M_E_CPU1_SA_DQS_DN<9>
J 0
(-3315 4735);
DISPLAY 0.659574 (-3315 4735);
PAINT MONO (-3315 4735);
DISPLAY INVISIBLE (-3315 4735);
FORCEPROP 1 LASTPIN (-3325 4725) BN 9
J 0
(-3337 4733);
DISPLAY 0.489362 (-3337 4733);
PAINT GREEN (-3337 4733);
FORCEPROP 2 LAST CDS_LIB mstr_standard
J 0
(-3275 4725);
DISPLAY 0.723404 (-3275 4725);
PAINT MONO (-3275 4725);
DISPLAY INVISIBLE (-3275 4725);
FORCEPROP 1 LAST BODY_TYPE PLUMBING
J 0
(-3275 4775);
DISPLAY 0.872340 (-3275 4775);
PAINT GREEN (-3275 4775);
DISPLAY INVISIBLE (-3275 4775);
FORCEPROP 1 LAST HDL_TAP TRUE
J 0
(-2950 4600);
DISPLAY 0.872340 (-2950 4600);
DISPLAY INVISIBLE (-2950 4600);
FORCEPROP 1 LAST PATH I199
J 0
(-3277 4725);
DISPLAY 0.872340 (-3277 4725);
PAINT GREEN (-3277 4725);
DISPLAY INVISIBLE (-3277 4725);
FORCEADD OFFPAGE..5
(-8475 2250);
FORCEPROP 2 LAST $XR0 41 
J 0
(-8699 2250);
DISPLAY 0.638298 (-8699 2250);
PAINT MONO (-8699 2250);
FORCEPROP 2 LAST PATH I2
J 0
(-8725 2300);
DISPLAY 1.021277 (-8725 2300);
DISPLAY INVISIBLE (-8725 2300);
FORCEPROP 1 LAST COMMENT_BODY TRUE
J 0
(-8375 2175);
DISPLAY 0.872340 (-8375 2175);
PAINT GREEN (-8375 2175);
DISPLAY INVISIBLE (-8375 2175);
FORCEPROP 1 LAST OFFPAGE TRUE
J 0
(-8150 2125);
DISPLAY 0.872340 (-8150 2125);
PAINT GREEN (-8150 2125);
DISPLAY INVISIBLE (-8150 2125);
FORCEPROP 2 LAST CDS_LIB mstr_standard
J 0
(-8475 2250);
DISPLAY 0.808511 (-8475 2250);
DISPLAY INVISIBLE (-8475 2250);
FORCEADD TAP..1
R 2
(-7875 4000);
FORCEPROP 3 LASTPIN (-7825 4000) SIG_NAME M_E_CPU1_SA_CB<2>
J 0
(-7815 4010);
DISPLAY 0.659574 (-7815 4010);
PAINT MONO (-7815 4010);
DISPLAY INVISIBLE (-7815 4010);
FORCEPROP 1 LASTPIN (-7825 4000) BN 2
J 2
(-7813 4008);
DISPLAY 0.489362 (-7813 4008);
PAINT GREEN (-7813 4008);
FORCEPROP 2 LAST CDS_LIB mstr_standard
J 0
(-7875 4000);
DISPLAY 0.723404 (-7875 4000);
PAINT MONO (-7875 4000);
DISPLAY INVISIBLE (-7875 4000);
FORCEPROP 1 LAST BODY_TYPE PLUMBING
J 2
(-7875 4050);
DISPLAY 0.872340 (-7875 4050);
PAINT GREEN (-7875 4050);
DISPLAY INVISIBLE (-7875 4050);
FORCEPROP 1 LAST HDL_TAP TRUE
J 2
(-8200 3875);
DISPLAY 0.872340 (-8200 3875);
DISPLAY INVISIBLE (-8200 3875);
FORCEPROP 1 LAST PATH I20
J 2
(-7873 4000);
DISPLAY 0.872340 (-7873 4000);
PAINT GREEN (-7873 4000);
DISPLAY INVISIBLE (-7873 4000);
FORCEADD TAP..1
(-3275 4425);
FORCEPROP 3 LASTPIN (-3325 4425) SIG_NAME M_E_CPU1_SA_DQS_DN<6>
J 0
(-3315 4435);
DISPLAY 0.659574 (-3315 4435);
PAINT MONO (-3315 4435);
DISPLAY INVISIBLE (-3315 4435);
FORCEPROP 1 LASTPIN (-3325 4425) BN 6
J 0
(-3337 4433);
DISPLAY 0.489362 (-3337 4433);
PAINT GREEN (-3337 4433);
FORCEPROP 2 LAST CDS_LIB mstr_standard
J 0
(-3275 4425);
DISPLAY 0.723404 (-3275 4425);
PAINT MONO (-3275 4425);
DISPLAY INVISIBLE (-3275 4425);
FORCEPROP 1 LAST BODY_TYPE PLUMBING
J 0
(-3275 4475);
DISPLAY 0.872340 (-3275 4475);
PAINT GREEN (-3275 4475);
DISPLAY INVISIBLE (-3275 4475);
FORCEPROP 1 LAST HDL_TAP TRUE
J 0
(-2950 4300);
DISPLAY 0.872340 (-2950 4300);
DISPLAY INVISIBLE (-2950 4300);
FORCEPROP 1 LAST PATH I200
J 0
(-3277 4425);
DISPLAY 0.872340 (-3277 4425);
PAINT GREEN (-3277 4425);
DISPLAY INVISIBLE (-3277 4425);
FORCEADD TAP..1
(-3275 4525);
FORCEPROP 3 LASTPIN (-3325 4525) SIG_NAME M_E_CPU1_SA_DQS_DN<7>
J 0
(-3315 4535);
DISPLAY 0.659574 (-3315 4535);
PAINT MONO (-3315 4535);
DISPLAY INVISIBLE (-3315 4535);
FORCEPROP 1 LASTPIN (-3325 4525) BN 7
J 0
(-3337 4533);
DISPLAY 0.489362 (-3337 4533);
PAINT GREEN (-3337 4533);
FORCEPROP 2 LAST CDS_LIB mstr_standard
J 0
(-3275 4525);
DISPLAY 0.723404 (-3275 4525);
PAINT MONO (-3275 4525);
DISPLAY INVISIBLE (-3275 4525);
FORCEPROP 1 LAST BODY_TYPE PLUMBING
J 0
(-3275 4575);
DISPLAY 0.872340 (-3275 4575);
PAINT GREEN (-3275 4575);
DISPLAY INVISIBLE (-3275 4575);
FORCEPROP 1 LAST HDL_TAP TRUE
J 0
(-2950 4400);
DISPLAY 0.872340 (-2950 4400);
DISPLAY INVISIBLE (-2950 4400);
FORCEPROP 1 LAST PATH I201
J 0
(-3277 4525);
DISPLAY 0.872340 (-3277 4525);
PAINT GREEN (-3277 4525);
DISPLAY INVISIBLE (-3277 4525);
FORCEADD TAP..1
(-3275 4325);
FORCEPROP 3 LASTPIN (-3325 4325) SIG_NAME M_E_CPU1_SA_DQS_DN<5>
J 0
(-3315 4335);
DISPLAY 0.659574 (-3315 4335);
PAINT MONO (-3315 4335);
DISPLAY INVISIBLE (-3315 4335);
FORCEPROP 1 LASTPIN (-3325 4325) BN 5
J 0
(-3337 4333);
DISPLAY 0.489362 (-3337 4333);
PAINT GREEN (-3337 4333);
FORCEPROP 2 LAST CDS_LIB mstr_standard
J 0
(-3275 4325);
DISPLAY 0.723404 (-3275 4325);
PAINT MONO (-3275 4325);
DISPLAY INVISIBLE (-3275 4325);
FORCEPROP 1 LAST BODY_TYPE PLUMBING
J 0
(-3275 4375);
DISPLAY 0.872340 (-3275 4375);
PAINT GREEN (-3275 4375);
DISPLAY INVISIBLE (-3275 4375);
FORCEPROP 1 LAST HDL_TAP TRUE
J 0
(-2950 4200);
DISPLAY 0.872340 (-2950 4200);
DISPLAY INVISIBLE (-2950 4200);
FORCEPROP 1 LAST PATH I202
J 0
(-3277 4325);
DISPLAY 0.872340 (-3277 4325);
PAINT GREEN (-3277 4325);
DISPLAY INVISIBLE (-3277 4325);
FORCEADD TAP..1
(-3475 4775);
FORCEPROP 3 LASTPIN (-3525 4775) SIG_NAME M_E_CPU1_SA_DQS_DP<9>
J 0
(-3515 4785);
DISPLAY 0.659574 (-3515 4785);
PAINT MONO (-3515 4785);
DISPLAY INVISIBLE (-3515 4785);
FORCEPROP 1 LASTPIN (-3525 4775) BN 9
J 0
(-3537 4783);
DISPLAY 0.489362 (-3537 4783);
PAINT GREEN (-3537 4783);
FORCEPROP 2 LAST CDS_LIB mstr_standard
J 0
(-3475 4775);
DISPLAY 0.723404 (-3475 4775);
PAINT MONO (-3475 4775);
DISPLAY INVISIBLE (-3475 4775);
FORCEPROP 1 LAST BODY_TYPE PLUMBING
J 0
(-3475 4825);
DISPLAY 0.872340 (-3475 4825);
PAINT GREEN (-3475 4825);
DISPLAY INVISIBLE (-3475 4825);
FORCEPROP 1 LAST HDL_TAP TRUE
J 0
(-3150 4650);
DISPLAY 0.872340 (-3150 4650);
DISPLAY INVISIBLE (-3150 4650);
FORCEPROP 1 LAST PATH I203
J 0
(-3477 4775);
DISPLAY 0.872340 (-3477 4775);
PAINT GREEN (-3477 4775);
DISPLAY INVISIBLE (-3477 4775);
FORCEADD TAP..1
(-3475 4675);
FORCEPROP 3 LASTPIN (-3525 4675) SIG_NAME M_E_CPU1_SA_DQS_DP<8>
J 0
(-3515 4685);
DISPLAY 0.659574 (-3515 4685);
PAINT MONO (-3515 4685);
DISPLAY INVISIBLE (-3515 4685);
FORCEPROP 1 LASTPIN (-3525 4675) BN 8
J 0
(-3537 4683);
DISPLAY 0.489362 (-3537 4683);
PAINT GREEN (-3537 4683);
FORCEPROP 2 LAST CDS_LIB mstr_standard
J 0
(-3475 4675);
DISPLAY 0.723404 (-3475 4675);
PAINT MONO (-3475 4675);
DISPLAY INVISIBLE (-3475 4675);
FORCEPROP 1 LAST BODY_TYPE PLUMBING
J 0
(-3475 4725);
DISPLAY 0.872340 (-3475 4725);
PAINT GREEN (-3475 4725);
DISPLAY INVISIBLE (-3475 4725);
FORCEPROP 1 LAST HDL_TAP TRUE
J 0
(-3150 4550);
DISPLAY 0.872340 (-3150 4550);
DISPLAY INVISIBLE (-3150 4550);
FORCEPROP 1 LAST PATH I204
J 0
(-3477 4675);
DISPLAY 0.872340 (-3477 4675);
PAINT GREEN (-3477 4675);
DISPLAY INVISIBLE (-3477 4675);
FORCEADD TAP..1
(-3475 4575);
FORCEPROP 3 LASTPIN (-3525 4575) SIG_NAME M_E_CPU1_SA_DQS_DP<7>
J 0
(-3515 4585);
DISPLAY 0.659574 (-3515 4585);
PAINT MONO (-3515 4585);
DISPLAY INVISIBLE (-3515 4585);
FORCEPROP 1 LASTPIN (-3525 4575) BN 7
J 0
(-3537 4583);
DISPLAY 0.489362 (-3537 4583);
PAINT GREEN (-3537 4583);
FORCEPROP 2 LAST CDS_LIB mstr_standard
J 0
(-3475 4575);
DISPLAY 0.723404 (-3475 4575);
PAINT MONO (-3475 4575);
DISPLAY INVISIBLE (-3475 4575);
FORCEPROP 1 LAST BODY_TYPE PLUMBING
J 0
(-3475 4625);
DISPLAY 0.872340 (-3475 4625);
PAINT GREEN (-3475 4625);
DISPLAY INVISIBLE (-3475 4625);
FORCEPROP 1 LAST HDL_TAP TRUE
J 0
(-3150 4450);
DISPLAY 0.872340 (-3150 4450);
DISPLAY INVISIBLE (-3150 4450);
FORCEPROP 1 LAST PATH I205
J 0
(-3477 4575);
DISPLAY 0.872340 (-3477 4575);
PAINT GREEN (-3477 4575);
DISPLAY INVISIBLE (-3477 4575);
FORCEADD TAP..1
(-3475 4475);
FORCEPROP 3 LASTPIN (-3525 4475) SIG_NAME M_E_CPU1_SA_DQS_DP<6>
J 0
(-3515 4485);
DISPLAY 0.659574 (-3515 4485);
PAINT MONO (-3515 4485);
DISPLAY INVISIBLE (-3515 4485);
FORCEPROP 1 LASTPIN (-3525 4475) BN 6
J 0
(-3537 4483);
DISPLAY 0.489362 (-3537 4483);
PAINT GREEN (-3537 4483);
FORCEPROP 2 LAST CDS_LIB mstr_standard
J 0
(-3475 4475);
DISPLAY 0.723404 (-3475 4475);
PAINT MONO (-3475 4475);
DISPLAY INVISIBLE (-3475 4475);
FORCEPROP 1 LAST BODY_TYPE PLUMBING
J 0
(-3475 4525);
DISPLAY 0.872340 (-3475 4525);
PAINT GREEN (-3475 4525);
DISPLAY INVISIBLE (-3475 4525);
FORCEPROP 1 LAST HDL_TAP TRUE
J 0
(-3150 4350);
DISPLAY 0.872340 (-3150 4350);
DISPLAY INVISIBLE (-3150 4350);
FORCEPROP 1 LAST PATH I206
J 0
(-3477 4475);
DISPLAY 0.872340 (-3477 4475);
PAINT GREEN (-3477 4475);
DISPLAY INVISIBLE (-3477 4475);
FORCEADD TAP..1
(-3475 4375);
FORCEPROP 3 LASTPIN (-3525 4375) SIG_NAME M_E_CPU1_SA_DQS_DP<5>
J 0
(-3515 4385);
DISPLAY 0.659574 (-3515 4385);
PAINT MONO (-3515 4385);
DISPLAY INVISIBLE (-3515 4385);
FORCEPROP 1 LASTPIN (-3525 4375) BN 5
J 0
(-3537 4383);
DISPLAY 0.489362 (-3537 4383);
PAINT GREEN (-3537 4383);
FORCEPROP 2 LAST CDS_LIB mstr_standard
J 0
(-3475 4375);
DISPLAY 0.723404 (-3475 4375);
PAINT MONO (-3475 4375);
DISPLAY INVISIBLE (-3475 4375);
FORCEPROP 1 LAST BODY_TYPE PLUMBING
J 0
(-3475 4425);
DISPLAY 0.872340 (-3475 4425);
PAINT GREEN (-3475 4425);
DISPLAY INVISIBLE (-3475 4425);
FORCEPROP 1 LAST HDL_TAP TRUE
J 0
(-3150 4250);
DISPLAY 0.872340 (-3150 4250);
DISPLAY INVISIBLE (-3150 4250);
FORCEPROP 1 LAST PATH I207
J 0
(-3477 4375);
DISPLAY 0.872340 (-3477 4375);
PAINT GREEN (-3477 4375);
DISPLAY INVISIBLE (-3477 4375);
FORCEADD TAP..1
(-3275 4225);
FORCEPROP 3 LASTPIN (-3325 4225) SIG_NAME M_E_CPU1_SA_DQS_DN<4>
J 0
(-3315 4235);
DISPLAY 0.659574 (-3315 4235);
PAINT MONO (-3315 4235);
DISPLAY INVISIBLE (-3315 4235);
FORCEPROP 1 LASTPIN (-3325 4225) BN 4
J 0
(-3337 4233);
DISPLAY 0.489362 (-3337 4233);
PAINT GREEN (-3337 4233);
FORCEPROP 2 LAST CDS_LIB mstr_standard
J 0
(-3275 4225);
DISPLAY 0.723404 (-3275 4225);
PAINT MONO (-3275 4225);
DISPLAY INVISIBLE (-3275 4225);
FORCEPROP 1 LAST BODY_TYPE PLUMBING
J 0
(-3275 4275);
DISPLAY 0.872340 (-3275 4275);
PAINT GREEN (-3275 4275);
DISPLAY INVISIBLE (-3275 4275);
FORCEPROP 1 LAST HDL_TAP TRUE
J 0
(-2950 4100);
DISPLAY 0.872340 (-2950 4100);
DISPLAY INVISIBLE (-2950 4100);
FORCEPROP 1 LAST PATH I208
J 0
(-3277 4225);
DISPLAY 0.872340 (-3277 4225);
PAINT GREEN (-3277 4225);
DISPLAY INVISIBLE (-3277 4225);
FORCEADD TAP..1
(-3275 4125);
FORCEPROP 3 LASTPIN (-3325 4125) SIG_NAME M_E_CPU1_SA_DQS_DN<3>
J 0
(-3315 4135);
DISPLAY 0.659574 (-3315 4135);
PAINT MONO (-3315 4135);
DISPLAY INVISIBLE (-3315 4135);
FORCEPROP 1 LASTPIN (-3325 4125) BN 3
J 0
(-3337 4133);
DISPLAY 0.489362 (-3337 4133);
PAINT GREEN (-3337 4133);
FORCEPROP 2 LAST CDS_LIB mstr_standard
J 0
(-3275 4125);
DISPLAY 0.723404 (-3275 4125);
PAINT MONO (-3275 4125);
DISPLAY INVISIBLE (-3275 4125);
FORCEPROP 1 LAST BODY_TYPE PLUMBING
J 0
(-3275 4175);
DISPLAY 0.872340 (-3275 4175);
PAINT GREEN (-3275 4175);
DISPLAY INVISIBLE (-3275 4175);
FORCEPROP 1 LAST HDL_TAP TRUE
J 0
(-2950 4000);
DISPLAY 0.872340 (-2950 4000);
DISPLAY INVISIBLE (-2950 4000);
FORCEPROP 1 LAST PATH I209
J 0
(-3277 4125);
DISPLAY 0.872340 (-3277 4125);
PAINT GREEN (-3277 4125);
DISPLAY INVISIBLE (-3277 4125);
FORCEADD TAP..1
R 2
(-7875 3950);
FORCEPROP 3 LASTPIN (-7825 3950) SIG_NAME M_E_CPU1_SA_CB<1>
J 0
(-7815 3960);
DISPLAY 0.659574 (-7815 3960);
PAINT MONO (-7815 3960);
DISPLAY INVISIBLE (-7815 3960);
FORCEPROP 1 LASTPIN (-7825 3950) BN 1
J 2
(-7813 3958);
DISPLAY 0.489362 (-7813 3958);
PAINT GREEN (-7813 3958);
FORCEPROP 2 LAST CDS_LIB mstr_standard
J 0
(-7875 3950);
DISPLAY 0.723404 (-7875 3950);
PAINT MONO (-7875 3950);
DISPLAY INVISIBLE (-7875 3950);
FORCEPROP 1 LAST BODY_TYPE PLUMBING
J 2
(-7875 4000);
DISPLAY 0.872340 (-7875 4000);
PAINT GREEN (-7875 4000);
DISPLAY INVISIBLE (-7875 4000);
FORCEPROP 1 LAST HDL_TAP TRUE
J 2
(-8200 3825);
DISPLAY 0.872340 (-8200 3825);
DISPLAY INVISIBLE (-8200 3825);
FORCEPROP 1 LAST PATH I21
J 2
(-7873 3950);
DISPLAY 0.872340 (-7873 3950);
PAINT GREEN (-7873 3950);
DISPLAY INVISIBLE (-7873 3950);
FORCEADD TAP..1
(-3275 3925);
FORCEPROP 3 LASTPIN (-3325 3925) SIG_NAME M_E_CPU1_SA_DQS_DN<1>
J 0
(-3315 3935);
DISPLAY 0.659574 (-3315 3935);
PAINT MONO (-3315 3935);
DISPLAY INVISIBLE (-3315 3935);
FORCEPROP 1 LASTPIN (-3325 3925) BN 1
J 0
(-3337 3933);
DISPLAY 0.489362 (-3337 3933);
PAINT GREEN (-3337 3933);
FORCEPROP 2 LAST CDS_LIB mstr_standard
J 0
(-3275 3925);
DISPLAY 0.723404 (-3275 3925);
PAINT MONO (-3275 3925);
DISPLAY INVISIBLE (-3275 3925);
FORCEPROP 1 LAST BODY_TYPE PLUMBING
J 0
(-3275 3975);
DISPLAY 0.872340 (-3275 3975);
PAINT GREEN (-3275 3975);
DISPLAY INVISIBLE (-3275 3975);
FORCEPROP 1 LAST HDL_TAP TRUE
J 0
(-2950 3800);
DISPLAY 0.872340 (-2950 3800);
DISPLAY INVISIBLE (-2950 3800);
FORCEPROP 1 LAST PATH I210
J 0
(-3277 3925);
DISPLAY 0.872340 (-3277 3925);
PAINT GREEN (-3277 3925);
DISPLAY INVISIBLE (-3277 3925);
FORCEADD TAP..1
(-3275 3825);
FORCEPROP 3 LASTPIN (-3325 3825) SIG_NAME M_E_CPU1_SA_DQS_DN<0>
J 0
(-3315 3835);
DISPLAY 0.659574 (-3315 3835);
PAINT MONO (-3315 3835);
DISPLAY INVISIBLE (-3315 3835);
FORCEPROP 1 LASTPIN (-3325 3825) BN 0
J 0
(-3337 3833);
DISPLAY 0.489362 (-3337 3833);
PAINT GREEN (-3337 3833);
FORCEPROP 2 LAST CDS_LIB mstr_standard
J 0
(-3275 3825);
DISPLAY 0.723404 (-3275 3825);
PAINT MONO (-3275 3825);
DISPLAY INVISIBLE (-3275 3825);
FORCEPROP 1 LAST BODY_TYPE PLUMBING
J 0
(-3275 3875);
DISPLAY 0.872340 (-3275 3875);
PAINT GREEN (-3275 3875);
DISPLAY INVISIBLE (-3275 3875);
FORCEPROP 1 LAST HDL_TAP TRUE
J 0
(-2950 3700);
DISPLAY 0.872340 (-2950 3700);
DISPLAY INVISIBLE (-2950 3700);
FORCEPROP 1 LAST PATH I211
J 0
(-3277 3825);
DISPLAY 0.872340 (-3277 3825);
PAINT GREEN (-3277 3825);
DISPLAY INVISIBLE (-3277 3825);
FORCEADD TAP..1
(-3475 4275);
FORCEPROP 3 LASTPIN (-3525 4275) SIG_NAME M_E_CPU1_SA_DQS_DP<4>
J 0
(-3515 4285);
DISPLAY 0.659574 (-3515 4285);
PAINT MONO (-3515 4285);
DISPLAY INVISIBLE (-3515 4285);
FORCEPROP 1 LASTPIN (-3525 4275) BN 4
J 0
(-3537 4283);
DISPLAY 0.489362 (-3537 4283);
PAINT GREEN (-3537 4283);
FORCEPROP 2 LAST CDS_LIB mstr_standard
J 0
(-3475 4275);
DISPLAY 0.723404 (-3475 4275);
PAINT MONO (-3475 4275);
DISPLAY INVISIBLE (-3475 4275);
FORCEPROP 1 LAST BODY_TYPE PLUMBING
J 0
(-3475 4325);
DISPLAY 0.872340 (-3475 4325);
PAINT GREEN (-3475 4325);
DISPLAY INVISIBLE (-3475 4325);
FORCEPROP 1 LAST HDL_TAP TRUE
J 0
(-3150 4150);
DISPLAY 0.872340 (-3150 4150);
DISPLAY INVISIBLE (-3150 4150);
FORCEPROP 1 LAST PATH I212
J 0
(-3477 4275);
DISPLAY 0.872340 (-3477 4275);
PAINT GREEN (-3477 4275);
DISPLAY INVISIBLE (-3477 4275);
FORCEADD TAP..1
(-3475 4175);
FORCEPROP 3 LASTPIN (-3525 4175) SIG_NAME M_E_CPU1_SA_DQS_DP<3>
J 0
(-3515 4185);
DISPLAY 0.659574 (-3515 4185);
PAINT MONO (-3515 4185);
DISPLAY INVISIBLE (-3515 4185);
FORCEPROP 1 LASTPIN (-3525 4175) BN 3
J 0
(-3537 4183);
DISPLAY 0.489362 (-3537 4183);
PAINT GREEN (-3537 4183);
FORCEPROP 2 LAST CDS_LIB mstr_standard
J 0
(-3475 4175);
DISPLAY 0.723404 (-3475 4175);
PAINT MONO (-3475 4175);
DISPLAY INVISIBLE (-3475 4175);
FORCEPROP 1 LAST BODY_TYPE PLUMBING
J 0
(-3475 4225);
DISPLAY 0.872340 (-3475 4225);
PAINT GREEN (-3475 4225);
DISPLAY INVISIBLE (-3475 4225);
FORCEPROP 1 LAST HDL_TAP TRUE
J 0
(-3150 4050);
DISPLAY 0.872340 (-3150 4050);
DISPLAY INVISIBLE (-3150 4050);
FORCEPROP 1 LAST PATH I213
J 0
(-3477 4175);
DISPLAY 0.872340 (-3477 4175);
PAINT GREEN (-3477 4175);
DISPLAY INVISIBLE (-3477 4175);
FORCEADD TAP..1
(-3475 4075);
FORCEPROP 3 LASTPIN (-3525 4075) SIG_NAME M_E_CPU1_SA_DQS_DP<2>
J 0
(-3515 4085);
DISPLAY 0.659574 (-3515 4085);
PAINT MONO (-3515 4085);
DISPLAY INVISIBLE (-3515 4085);
FORCEPROP 1 LASTPIN (-3525 4075) BN 2
J 0
(-3537 4083);
DISPLAY 0.489362 (-3537 4083);
PAINT GREEN (-3537 4083);
FORCEPROP 2 LAST CDS_LIB mstr_standard
J 0
(-3475 4075);
DISPLAY 0.723404 (-3475 4075);
PAINT MONO (-3475 4075);
DISPLAY INVISIBLE (-3475 4075);
FORCEPROP 1 LAST BODY_TYPE PLUMBING
J 0
(-3475 4125);
DISPLAY 0.872340 (-3475 4125);
PAINT GREEN (-3475 4125);
DISPLAY INVISIBLE (-3475 4125);
FORCEPROP 1 LAST HDL_TAP TRUE
J 0
(-3150 3950);
DISPLAY 0.872340 (-3150 3950);
DISPLAY INVISIBLE (-3150 3950);
FORCEPROP 1 LAST PATH I214
J 0
(-3477 4075);
DISPLAY 0.872340 (-3477 4075);
PAINT GREEN (-3477 4075);
DISPLAY INVISIBLE (-3477 4075);
FORCEADD TAP..1
(-3475 3975);
FORCEPROP 3 LASTPIN (-3525 3975) SIG_NAME M_E_CPU1_SA_DQS_DP<1>
J 0
(-3515 3985);
DISPLAY 0.659574 (-3515 3985);
PAINT MONO (-3515 3985);
DISPLAY INVISIBLE (-3515 3985);
FORCEPROP 1 LASTPIN (-3525 3975) BN 1
J 0
(-3537 3983);
DISPLAY 0.489362 (-3537 3983);
PAINT GREEN (-3537 3983);
FORCEPROP 2 LAST CDS_LIB mstr_standard
J 0
(-3475 3975);
DISPLAY 0.723404 (-3475 3975);
PAINT MONO (-3475 3975);
DISPLAY INVISIBLE (-3475 3975);
FORCEPROP 1 LAST BODY_TYPE PLUMBING
J 0
(-3475 4025);
DISPLAY 0.872340 (-3475 4025);
PAINT GREEN (-3475 4025);
DISPLAY INVISIBLE (-3475 4025);
FORCEPROP 1 LAST HDL_TAP TRUE
J 0
(-3150 3850);
DISPLAY 0.872340 (-3150 3850);
DISPLAY INVISIBLE (-3150 3850);
FORCEPROP 1 LAST PATH I215
J 0
(-3477 3975);
DISPLAY 0.872340 (-3477 3975);
PAINT GREEN (-3477 3975);
DISPLAY INVISIBLE (-3477 3975);
FORCEADD TAP..1
(-3275 3575);
FORCEPROP 3 LASTPIN (-3325 3575) SIG_NAME M_E_CPU1_SB_DQS_DN<8>
J 0
(-3315 3585);
DISPLAY 0.659574 (-3315 3585);
PAINT MONO (-3315 3585);
DISPLAY INVISIBLE (-3315 3585);
FORCEPROP 1 LASTPIN (-3325 3575) BN 8
J 0
(-3337 3583);
DISPLAY 0.489362 (-3337 3583);
PAINT GREEN (-3337 3583);
FORCEPROP 2 LAST CDS_LIB mstr_standard
J 0
(-3275 3575);
DISPLAY 0.723404 (-3275 3575);
PAINT MONO (-3275 3575);
DISPLAY INVISIBLE (-3275 3575);
FORCEPROP 1 LAST BODY_TYPE PLUMBING
J 0
(-3275 3625);
DISPLAY 0.872340 (-3275 3625);
PAINT GREEN (-3275 3625);
DISPLAY INVISIBLE (-3275 3625);
FORCEPROP 1 LAST HDL_TAP TRUE
J 0
(-2950 3450);
DISPLAY 0.872340 (-2950 3450);
DISPLAY INVISIBLE (-2950 3450);
FORCEPROP 1 LAST PATH I216
J 0
(-3277 3575);
DISPLAY 0.872340 (-3277 3575);
PAINT GREEN (-3277 3575);
DISPLAY INVISIBLE (-3277 3575);
FORCEADD TAP..1
(-3275 3675);
FORCEPROP 3 LASTPIN (-3325 3675) SIG_NAME M_E_CPU1_SB_DQS_DN<9>
J 0
(-3315 3685);
DISPLAY 0.659574 (-3315 3685);
PAINT MONO (-3315 3685);
DISPLAY INVISIBLE (-3315 3685);
FORCEPROP 1 LASTPIN (-3325 3675) BN 9
J 0
(-3337 3683);
DISPLAY 0.489362 (-3337 3683);
PAINT GREEN (-3337 3683);
FORCEPROP 2 LAST CDS_LIB mstr_standard
J 0
(-3275 3675);
DISPLAY 0.723404 (-3275 3675);
PAINT MONO (-3275 3675);
DISPLAY INVISIBLE (-3275 3675);
FORCEPROP 1 LAST BODY_TYPE PLUMBING
J 0
(-3275 3725);
DISPLAY 0.872340 (-3275 3725);
PAINT GREEN (-3275 3725);
DISPLAY INVISIBLE (-3275 3725);
FORCEPROP 1 LAST HDL_TAP TRUE
J 0
(-2950 3550);
DISPLAY 0.872340 (-2950 3550);
DISPLAY INVISIBLE (-2950 3550);
FORCEPROP 1 LAST PATH I217
J 0
(-3277 3675);
DISPLAY 0.872340 (-3277 3675);
PAINT GREEN (-3277 3675);
DISPLAY INVISIBLE (-3277 3675);
FORCEADD TAP..1
(-3275 3375);
FORCEPROP 3 LASTPIN (-3325 3375) SIG_NAME M_E_CPU1_SB_DQS_DN<6>
J 0
(-3315 3385);
DISPLAY 0.659574 (-3315 3385);
PAINT MONO (-3315 3385);
DISPLAY INVISIBLE (-3315 3385);
FORCEPROP 1 LASTPIN (-3325 3375) BN 6
J 0
(-3337 3383);
DISPLAY 0.489362 (-3337 3383);
PAINT GREEN (-3337 3383);
FORCEPROP 2 LAST CDS_LIB mstr_standard
J 0
(-3275 3375);
DISPLAY 0.723404 (-3275 3375);
PAINT MONO (-3275 3375);
DISPLAY INVISIBLE (-3275 3375);
FORCEPROP 1 LAST BODY_TYPE PLUMBING
J 0
(-3275 3425);
DISPLAY 0.872340 (-3275 3425);
PAINT GREEN (-3275 3425);
DISPLAY INVISIBLE (-3275 3425);
FORCEPROP 1 LAST HDL_TAP TRUE
J 0
(-2950 3250);
DISPLAY 0.872340 (-2950 3250);
DISPLAY INVISIBLE (-2950 3250);
FORCEPROP 1 LAST PATH I218
J 0
(-3277 3375);
DISPLAY 0.872340 (-3277 3375);
PAINT GREEN (-3277 3375);
DISPLAY INVISIBLE (-3277 3375);
FORCEADD TAP..1
(-3275 3475);
FORCEPROP 3 LASTPIN (-3325 3475) SIG_NAME M_E_CPU1_SB_DQS_DN<7>
J 0
(-3315 3485);
DISPLAY 0.659574 (-3315 3485);
PAINT MONO (-3315 3485);
DISPLAY INVISIBLE (-3315 3485);
FORCEPROP 1 LASTPIN (-3325 3475) BN 7
J 0
(-3337 3483);
DISPLAY 0.489362 (-3337 3483);
PAINT GREEN (-3337 3483);
FORCEPROP 2 LAST CDS_LIB mstr_standard
J 0
(-3275 3475);
DISPLAY 0.723404 (-3275 3475);
PAINT MONO (-3275 3475);
DISPLAY INVISIBLE (-3275 3475);
FORCEPROP 1 LAST BODY_TYPE PLUMBING
J 0
(-3275 3525);
DISPLAY 0.872340 (-3275 3525);
PAINT GREEN (-3275 3525);
DISPLAY INVISIBLE (-3275 3525);
FORCEPROP 1 LAST HDL_TAP TRUE
J 0
(-2950 3350);
DISPLAY 0.872340 (-2950 3350);
DISPLAY INVISIBLE (-2950 3350);
FORCEPROP 1 LAST PATH I219
J 0
(-3277 3475);
DISPLAY 0.872340 (-3277 3475);
PAINT GREEN (-3277 3475);
DISPLAY INVISIBLE (-3277 3475);
FORCEADD TAP..1
R 2
(-7875 4050);
FORCEPROP 3 LASTPIN (-7825 4050) SIG_NAME M_E_CPU1_SA_CB<3>
J 0
(-7815 4060);
DISPLAY 0.659574 (-7815 4060);
PAINT MONO (-7815 4060);
DISPLAY INVISIBLE (-7815 4060);
FORCEPROP 1 LASTPIN (-7825 4050) BN 3
J 2
(-7813 4058);
DISPLAY 0.489362 (-7813 4058);
PAINT GREEN (-7813 4058);
FORCEPROP 2 LAST CDS_LIB mstr_standard
J 0
(-7875 4050);
DISPLAY 0.723404 (-7875 4050);
PAINT MONO (-7875 4050);
DISPLAY INVISIBLE (-7875 4050);
FORCEPROP 1 LAST BODY_TYPE PLUMBING
J 2
(-7875 4100);
DISPLAY 0.872340 (-7875 4100);
PAINT GREEN (-7875 4100);
DISPLAY INVISIBLE (-7875 4100);
FORCEPROP 1 LAST HDL_TAP TRUE
J 2
(-8200 3925);
DISPLAY 0.872340 (-8200 3925);
DISPLAY INVISIBLE (-8200 3925);
FORCEPROP 1 LAST PATH I22
J 2
(-7873 4050);
DISPLAY 0.872340 (-7873 4050);
PAINT GREEN (-7873 4050);
DISPLAY INVISIBLE (-7873 4050);
FORCEADD TAP..1
(-3475 3725);
FORCEPROP 3 LASTPIN (-3525 3725) SIG_NAME M_E_CPU1_SB_DQS_DP<9>
J 0
(-3515 3735);
DISPLAY 0.659574 (-3515 3735);
PAINT MONO (-3515 3735);
DISPLAY INVISIBLE (-3515 3735);
FORCEPROP 1 LASTPIN (-3525 3725) BN 9
J 0
(-3537 3733);
DISPLAY 0.489362 (-3537 3733);
PAINT GREEN (-3537 3733);
FORCEPROP 2 LAST CDS_LIB mstr_standard
J 0
(-3475 3725);
DISPLAY 0.723404 (-3475 3725);
PAINT MONO (-3475 3725);
DISPLAY INVISIBLE (-3475 3725);
FORCEPROP 1 LAST BODY_TYPE PLUMBING
J 0
(-3475 3775);
DISPLAY 0.872340 (-3475 3775);
PAINT GREEN (-3475 3775);
DISPLAY INVISIBLE (-3475 3775);
FORCEPROP 1 LAST HDL_TAP TRUE
J 0
(-3150 3600);
DISPLAY 0.872340 (-3150 3600);
DISPLAY INVISIBLE (-3150 3600);
FORCEPROP 1 LAST PATH I220
J 0
(-3477 3725);
DISPLAY 0.872340 (-3477 3725);
PAINT GREEN (-3477 3725);
DISPLAY INVISIBLE (-3477 3725);
FORCEADD TAP..1
(-3475 3625);
FORCEPROP 3 LASTPIN (-3525 3625) SIG_NAME M_E_CPU1_SB_DQS_DP<8>
J 0
(-3515 3635);
DISPLAY 0.659574 (-3515 3635);
PAINT MONO (-3515 3635);
DISPLAY INVISIBLE (-3515 3635);
FORCEPROP 1 LASTPIN (-3525 3625) BN 8
J 0
(-3537 3633);
DISPLAY 0.489362 (-3537 3633);
PAINT GREEN (-3537 3633);
FORCEPROP 2 LAST CDS_LIB mstr_standard
J 0
(-3475 3625);
DISPLAY 0.723404 (-3475 3625);
PAINT MONO (-3475 3625);
DISPLAY INVISIBLE (-3475 3625);
FORCEPROP 1 LAST BODY_TYPE PLUMBING
J 0
(-3475 3675);
DISPLAY 0.872340 (-3475 3675);
PAINT GREEN (-3475 3675);
DISPLAY INVISIBLE (-3475 3675);
FORCEPROP 1 LAST HDL_TAP TRUE
J 0
(-3150 3500);
DISPLAY 0.872340 (-3150 3500);
DISPLAY INVISIBLE (-3150 3500);
FORCEPROP 1 LAST PATH I221
J 0
(-3477 3625);
DISPLAY 0.872340 (-3477 3625);
PAINT GREEN (-3477 3625);
DISPLAY INVISIBLE (-3477 3625);
FORCEADD TAP..1
(-3475 3525);
FORCEPROP 3 LASTPIN (-3525 3525) SIG_NAME M_E_CPU1_SB_DQS_DP<7>
J 0
(-3515 3535);
DISPLAY 0.659574 (-3515 3535);
PAINT MONO (-3515 3535);
DISPLAY INVISIBLE (-3515 3535);
FORCEPROP 1 LASTPIN (-3525 3525) BN 7
J 0
(-3537 3533);
DISPLAY 0.489362 (-3537 3533);
PAINT GREEN (-3537 3533);
FORCEPROP 2 LAST CDS_LIB mstr_standard
J 0
(-3475 3525);
DISPLAY 0.723404 (-3475 3525);
PAINT MONO (-3475 3525);
DISPLAY INVISIBLE (-3475 3525);
FORCEPROP 1 LAST BODY_TYPE PLUMBING
J 0
(-3475 3575);
DISPLAY 0.872340 (-3475 3575);
PAINT GREEN (-3475 3575);
DISPLAY INVISIBLE (-3475 3575);
FORCEPROP 1 LAST HDL_TAP TRUE
J 0
(-3150 3400);
DISPLAY 0.872340 (-3150 3400);
DISPLAY INVISIBLE (-3150 3400);
FORCEPROP 1 LAST PATH I222
J 0
(-3477 3525);
DISPLAY 0.872340 (-3477 3525);
PAINT GREEN (-3477 3525);
DISPLAY INVISIBLE (-3477 3525);
FORCEADD TAP..1
(-3475 3425);
FORCEPROP 3 LASTPIN (-3525 3425) SIG_NAME M_E_CPU1_SB_DQS_DP<6>
J 0
(-3515 3435);
DISPLAY 0.659574 (-3515 3435);
PAINT MONO (-3515 3435);
DISPLAY INVISIBLE (-3515 3435);
FORCEPROP 1 LASTPIN (-3525 3425) BN 6
J 0
(-3537 3433);
DISPLAY 0.489362 (-3537 3433);
PAINT GREEN (-3537 3433);
FORCEPROP 2 LAST CDS_LIB mstr_standard
J 0
(-3475 3425);
DISPLAY 0.723404 (-3475 3425);
PAINT MONO (-3475 3425);
DISPLAY INVISIBLE (-3475 3425);
FORCEPROP 1 LAST BODY_TYPE PLUMBING
J 0
(-3475 3475);
DISPLAY 0.872340 (-3475 3475);
PAINT GREEN (-3475 3475);
DISPLAY INVISIBLE (-3475 3475);
FORCEPROP 1 LAST HDL_TAP TRUE
J 0
(-3150 3300);
DISPLAY 0.872340 (-3150 3300);
DISPLAY INVISIBLE (-3150 3300);
FORCEPROP 1 LAST PATH I223
J 0
(-3477 3425);
DISPLAY 0.872340 (-3477 3425);
PAINT GREEN (-3477 3425);
DISPLAY INVISIBLE (-3477 3425);
FORCEADD TAP..1
(-3475 3325);
FORCEPROP 3 LASTPIN (-3525 3325) SIG_NAME M_E_CPU1_SB_DQS_DP<5>
J 0
(-3515 3335);
DISPLAY 0.659574 (-3515 3335);
PAINT MONO (-3515 3335);
DISPLAY INVISIBLE (-3515 3335);
FORCEPROP 1 LASTPIN (-3525 3325) BN 5
J 0
(-3537 3333);
DISPLAY 0.489362 (-3537 3333);
PAINT GREEN (-3537 3333);
FORCEPROP 2 LAST CDS_LIB mstr_standard
J 0
(-3475 3325);
DISPLAY 0.723404 (-3475 3325);
PAINT MONO (-3475 3325);
DISPLAY INVISIBLE (-3475 3325);
FORCEPROP 1 LAST BODY_TYPE PLUMBING
J 0
(-3475 3375);
DISPLAY 0.872340 (-3475 3375);
PAINT GREEN (-3475 3375);
DISPLAY INVISIBLE (-3475 3375);
FORCEPROP 1 LAST HDL_TAP TRUE
J 0
(-3150 3200);
DISPLAY 0.872340 (-3150 3200);
DISPLAY INVISIBLE (-3150 3200);
FORCEPROP 1 LAST PATH I224
J 0
(-3477 3325);
DISPLAY 0.872340 (-3477 3325);
PAINT GREEN (-3477 3325);
DISPLAY INVISIBLE (-3477 3325);
FORCEADD TAP..1
(-3275 3075);
FORCEPROP 3 LASTPIN (-3325 3075) SIG_NAME M_E_CPU1_SB_DQS_DN<3>
J 0
(-3315 3085);
DISPLAY 0.659574 (-3315 3085);
PAINT MONO (-3315 3085);
DISPLAY INVISIBLE (-3315 3085);
FORCEPROP 1 LASTPIN (-3325 3075) BN 3
J 0
(-3337 3083);
DISPLAY 0.489362 (-3337 3083);
PAINT GREEN (-3337 3083);
FORCEPROP 2 LAST CDS_LIB mstr_standard
J 0
(-3275 3075);
DISPLAY 0.723404 (-3275 3075);
PAINT MONO (-3275 3075);
DISPLAY INVISIBLE (-3275 3075);
FORCEPROP 1 LAST BODY_TYPE PLUMBING
J 0
(-3275 3125);
DISPLAY 0.872340 (-3275 3125);
PAINT GREEN (-3275 3125);
DISPLAY INVISIBLE (-3275 3125);
FORCEPROP 1 LAST HDL_TAP TRUE
J 0
(-2950 2950);
DISPLAY 0.872340 (-2950 2950);
DISPLAY INVISIBLE (-2950 2950);
FORCEPROP 1 LAST PATH I225
J 0
(-3277 3075);
DISPLAY 0.872340 (-3277 3075);
PAINT GREEN (-3277 3075);
DISPLAY INVISIBLE (-3277 3075);
FORCEADD TAP..1
(-3275 3275);
FORCEPROP 3 LASTPIN (-3325 3275) SIG_NAME M_E_CPU1_SB_DQS_DN<5>
J 0
(-3315 3285);
DISPLAY 0.659574 (-3315 3285);
PAINT MONO (-3315 3285);
DISPLAY INVISIBLE (-3315 3285);
FORCEPROP 1 LASTPIN (-3325 3275) BN 5
J 0
(-3337 3283);
DISPLAY 0.489362 (-3337 3283);
PAINT GREEN (-3337 3283);
FORCEPROP 2 LAST CDS_LIB mstr_standard
J 0
(-3275 3275);
DISPLAY 0.723404 (-3275 3275);
PAINT MONO (-3275 3275);
DISPLAY INVISIBLE (-3275 3275);
FORCEPROP 1 LAST BODY_TYPE PLUMBING
J 0
(-3275 3325);
DISPLAY 0.872340 (-3275 3325);
PAINT GREEN (-3275 3325);
DISPLAY INVISIBLE (-3275 3325);
FORCEPROP 1 LAST HDL_TAP TRUE
J 0
(-2950 3150);
DISPLAY 0.872340 (-2950 3150);
DISPLAY INVISIBLE (-2950 3150);
FORCEPROP 1 LAST PATH I226
J 0
(-3277 3275);
DISPLAY 0.872340 (-3277 3275);
PAINT GREEN (-3277 3275);
DISPLAY INVISIBLE (-3277 3275);
FORCEADD TAP..1
(-3275 3175);
FORCEPROP 3 LASTPIN (-3325 3175) SIG_NAME M_E_CPU1_SB_DQS_DN<4>
J 0
(-3315 3185);
DISPLAY 0.659574 (-3315 3185);
PAINT MONO (-3315 3185);
DISPLAY INVISIBLE (-3315 3185);
FORCEPROP 1 LASTPIN (-3325 3175) BN 4
J 0
(-3337 3183);
DISPLAY 0.489362 (-3337 3183);
PAINT GREEN (-3337 3183);
FORCEPROP 2 LAST CDS_LIB mstr_standard
J 0
(-3275 3175);
DISPLAY 0.723404 (-3275 3175);
PAINT MONO (-3275 3175);
DISPLAY INVISIBLE (-3275 3175);
FORCEPROP 1 LAST BODY_TYPE PLUMBING
J 0
(-3275 3225);
DISPLAY 0.872340 (-3275 3225);
PAINT GREEN (-3275 3225);
DISPLAY INVISIBLE (-3275 3225);
FORCEPROP 1 LAST HDL_TAP TRUE
J 0
(-2950 3050);
DISPLAY 0.872340 (-2950 3050);
DISPLAY INVISIBLE (-2950 3050);
FORCEPROP 1 LAST PATH I227
J 0
(-3277 3175);
DISPLAY 0.872340 (-3277 3175);
PAINT GREEN (-3277 3175);
DISPLAY INVISIBLE (-3277 3175);
FORCEADD TAP..1
(-3275 2875);
FORCEPROP 3 LASTPIN (-3325 2875) SIG_NAME M_E_CPU1_SB_DQS_DN<1>
J 0
(-3315 2885);
DISPLAY 0.659574 (-3315 2885);
PAINT MONO (-3315 2885);
DISPLAY INVISIBLE (-3315 2885);
FORCEPROP 1 LASTPIN (-3325 2875) BN 1
J 0
(-3337 2883);
DISPLAY 0.489362 (-3337 2883);
PAINT GREEN (-3337 2883);
FORCEPROP 2 LAST CDS_LIB mstr_standard
J 0
(-3275 2875);
DISPLAY 0.723404 (-3275 2875);
PAINT MONO (-3275 2875);
DISPLAY INVISIBLE (-3275 2875);
FORCEPROP 1 LAST BODY_TYPE PLUMBING
J 0
(-3275 2925);
DISPLAY 0.872340 (-3275 2925);
PAINT GREEN (-3275 2925);
DISPLAY INVISIBLE (-3275 2925);
FORCEPROP 1 LAST HDL_TAP TRUE
J 0
(-2950 2750);
DISPLAY 0.872340 (-2950 2750);
DISPLAY INVISIBLE (-2950 2750);
FORCEPROP 1 LAST PATH I228
J 0
(-3277 2875);
DISPLAY 0.872340 (-3277 2875);
PAINT GREEN (-3277 2875);
DISPLAY INVISIBLE (-3277 2875);
FORCEADD TAP..1
(-3275 2975);
FORCEPROP 3 LASTPIN (-3325 2975) SIG_NAME M_E_CPU1_SB_DQS_DN<2>
J 0
(-3315 2985);
DISPLAY 0.659574 (-3315 2985);
PAINT MONO (-3315 2985);
DISPLAY INVISIBLE (-3315 2985);
FORCEPROP 1 LASTPIN (-3325 2975) BN 2
J 0
(-3337 2983);
DISPLAY 0.489362 (-3337 2983);
PAINT GREEN (-3337 2983);
FORCEPROP 2 LAST CDS_LIB mstr_standard
J 0
(-3275 2975);
DISPLAY 0.723404 (-3275 2975);
PAINT MONO (-3275 2975);
DISPLAY INVISIBLE (-3275 2975);
FORCEPROP 1 LAST BODY_TYPE PLUMBING
J 0
(-3275 3025);
DISPLAY 0.872340 (-3275 3025);
PAINT GREEN (-3275 3025);
DISPLAY INVISIBLE (-3275 3025);
FORCEPROP 1 LAST HDL_TAP TRUE
J 0
(-2950 2850);
DISPLAY 0.872340 (-2950 2850);
DISPLAY INVISIBLE (-2950 2850);
FORCEPROP 1 LAST PATH I229
J 0
(-3277 2975);
DISPLAY 0.872340 (-3277 2975);
PAINT GREEN (-3277 2975);
DISPLAY INVISIBLE (-3277 2975);
FORCEADD TAP..1
R 2
(-7875 4100);
FORCEPROP 3 LASTPIN (-7825 4100) SIG_NAME M_E_CPU1_SA_CB<4>
J 0
(-7815 4110);
DISPLAY 0.659574 (-7815 4110);
PAINT MONO (-7815 4110);
DISPLAY INVISIBLE (-7815 4110);
FORCEPROP 1 LASTPIN (-7825 4100) BN 4
J 2
(-7813 4108);
DISPLAY 0.489362 (-7813 4108);
PAINT GREEN (-7813 4108);
FORCEPROP 2 LAST CDS_LIB mstr_standard
J 0
(-7875 4100);
DISPLAY 0.723404 (-7875 4100);
PAINT MONO (-7875 4100);
DISPLAY INVISIBLE (-7875 4100);
FORCEPROP 1 LAST BODY_TYPE PLUMBING
J 2
(-7875 4150);
DISPLAY 0.872340 (-7875 4150);
PAINT GREEN (-7875 4150);
DISPLAY INVISIBLE (-7875 4150);
FORCEPROP 1 LAST HDL_TAP TRUE
J 2
(-8200 3975);
DISPLAY 0.872340 (-8200 3975);
DISPLAY INVISIBLE (-8200 3975);
FORCEPROP 1 LAST PATH I23
J 2
(-7873 4100);
DISPLAY 0.872340 (-7873 4100);
PAINT GREEN (-7873 4100);
DISPLAY INVISIBLE (-7873 4100);
FORCEADD TAP..1
(-3475 3225);
FORCEPROP 3 LASTPIN (-3525 3225) SIG_NAME M_E_CPU1_SB_DQS_DP<4>
J 0
(-3515 3235);
DISPLAY 0.659574 (-3515 3235);
PAINT MONO (-3515 3235);
DISPLAY INVISIBLE (-3515 3235);
FORCEPROP 1 LASTPIN (-3525 3225) BN 4
J 0
(-3537 3233);
DISPLAY 0.489362 (-3537 3233);
PAINT GREEN (-3537 3233);
FORCEPROP 2 LAST CDS_LIB mstr_standard
J 0
(-3475 3225);
DISPLAY 0.723404 (-3475 3225);
PAINT MONO (-3475 3225);
DISPLAY INVISIBLE (-3475 3225);
FORCEPROP 1 LAST BODY_TYPE PLUMBING
J 0
(-3475 3275);
DISPLAY 0.872340 (-3475 3275);
PAINT GREEN (-3475 3275);
DISPLAY INVISIBLE (-3475 3275);
FORCEPROP 1 LAST HDL_TAP TRUE
J 0
(-3150 3100);
DISPLAY 0.872340 (-3150 3100);
DISPLAY INVISIBLE (-3150 3100);
FORCEPROP 1 LAST PATH I230
J 0
(-3477 3225);
DISPLAY 0.872340 (-3477 3225);
PAINT GREEN (-3477 3225);
DISPLAY INVISIBLE (-3477 3225);
FORCEADD TAP..1
(-3475 3125);
FORCEPROP 3 LASTPIN (-3525 3125) SIG_NAME M_E_CPU1_SB_DQS_DP<3>
J 0
(-3515 3135);
DISPLAY 0.659574 (-3515 3135);
PAINT MONO (-3515 3135);
DISPLAY INVISIBLE (-3515 3135);
FORCEPROP 1 LASTPIN (-3525 3125) BN 3
J 0
(-3537 3133);
DISPLAY 0.489362 (-3537 3133);
PAINT GREEN (-3537 3133);
FORCEPROP 2 LAST CDS_LIB mstr_standard
J 0
(-3475 3125);
DISPLAY 0.723404 (-3475 3125);
PAINT MONO (-3475 3125);
DISPLAY INVISIBLE (-3475 3125);
FORCEPROP 1 LAST BODY_TYPE PLUMBING
J 0
(-3475 3175);
DISPLAY 0.872340 (-3475 3175);
PAINT GREEN (-3475 3175);
DISPLAY INVISIBLE (-3475 3175);
FORCEPROP 1 LAST HDL_TAP TRUE
J 0
(-3150 3000);
DISPLAY 0.872340 (-3150 3000);
DISPLAY INVISIBLE (-3150 3000);
FORCEPROP 1 LAST PATH I231
J 0
(-3477 3125);
DISPLAY 0.872340 (-3477 3125);
PAINT GREEN (-3477 3125);
DISPLAY INVISIBLE (-3477 3125);
FORCEADD TAP..1
(-3475 3025);
FORCEPROP 3 LASTPIN (-3525 3025) SIG_NAME M_E_CPU1_SB_DQS_DP<2>
J 0
(-3515 3035);
DISPLAY 0.659574 (-3515 3035);
PAINT MONO (-3515 3035);
DISPLAY INVISIBLE (-3515 3035);
FORCEPROP 1 LASTPIN (-3525 3025) BN 2
J 0
(-3537 3033);
DISPLAY 0.489362 (-3537 3033);
PAINT GREEN (-3537 3033);
FORCEPROP 2 LAST CDS_LIB mstr_standard
J 0
(-3475 3025);
DISPLAY 0.723404 (-3475 3025);
PAINT MONO (-3475 3025);
DISPLAY INVISIBLE (-3475 3025);
FORCEPROP 1 LAST BODY_TYPE PLUMBING
J 0
(-3475 3075);
DISPLAY 0.872340 (-3475 3075);
PAINT GREEN (-3475 3075);
DISPLAY INVISIBLE (-3475 3075);
FORCEPROP 1 LAST HDL_TAP TRUE
J 0
(-3150 2900);
DISPLAY 0.872340 (-3150 2900);
DISPLAY INVISIBLE (-3150 2900);
FORCEPROP 1 LAST PATH I232
J 0
(-3477 3025);
DISPLAY 0.872340 (-3477 3025);
PAINT GREEN (-3477 3025);
DISPLAY INVISIBLE (-3477 3025);
FORCEADD TAP..1
(-3475 2925);
FORCEPROP 3 LASTPIN (-3525 2925) SIG_NAME M_E_CPU1_SB_DQS_DP<1>
J 0
(-3515 2935);
DISPLAY 0.659574 (-3515 2935);
PAINT MONO (-3515 2935);
DISPLAY INVISIBLE (-3515 2935);
FORCEPROP 1 LASTPIN (-3525 2925) BN 1
J 0
(-3537 2933);
DISPLAY 0.489362 (-3537 2933);
PAINT GREEN (-3537 2933);
FORCEPROP 2 LAST CDS_LIB mstr_standard
J 0
(-3475 2925);
DISPLAY 0.723404 (-3475 2925);
PAINT MONO (-3475 2925);
DISPLAY INVISIBLE (-3475 2925);
FORCEPROP 1 LAST BODY_TYPE PLUMBING
J 0
(-3475 2975);
DISPLAY 0.872340 (-3475 2975);
PAINT GREEN (-3475 2975);
DISPLAY INVISIBLE (-3475 2975);
FORCEPROP 1 LAST HDL_TAP TRUE
J 0
(-3150 2800);
DISPLAY 0.872340 (-3150 2800);
DISPLAY INVISIBLE (-3150 2800);
FORCEPROP 1 LAST PATH I233
J 0
(-3477 2925);
DISPLAY 0.872340 (-3477 2925);
PAINT GREEN (-3477 2925);
DISPLAY INVISIBLE (-3477 2925);
FORCEADD TAP..1
(-3475 2825);
FORCEPROP 3 LASTPIN (-3525 2825) SIG_NAME M_E_CPU1_SB_DQS_DP<0>
J 0
(-3515 2835);
DISPLAY 0.659574 (-3515 2835);
PAINT MONO (-3515 2835);
DISPLAY INVISIBLE (-3515 2835);
FORCEPROP 1 LASTPIN (-3525 2825) BN 0
J 0
(-3537 2833);
DISPLAY 0.489362 (-3537 2833);
PAINT GREEN (-3537 2833);
FORCEPROP 2 LAST CDS_LIB mstr_standard
J 0
(-3475 2825);
DISPLAY 0.723404 (-3475 2825);
PAINT MONO (-3475 2825);
DISPLAY INVISIBLE (-3475 2825);
FORCEPROP 1 LAST BODY_TYPE PLUMBING
J 0
(-3475 2875);
DISPLAY 0.872340 (-3475 2875);
PAINT GREEN (-3475 2875);
DISPLAY INVISIBLE (-3475 2875);
FORCEPROP 1 LAST HDL_TAP TRUE
J 0
(-3150 2700);
DISPLAY 0.872340 (-3150 2700);
DISPLAY INVISIBLE (-3150 2700);
FORCEPROP 1 LAST PATH I234
J 0
(-3477 2825);
DISPLAY 0.872340 (-3477 2825);
PAINT GREEN (-3477 2825);
DISPLAY INVISIBLE (-3477 2825);
FORCEADD TAP..1
(-3275 2775);
FORCEPROP 3 LASTPIN (-3325 2775) SIG_NAME M_E_CPU1_SB_DQS_DN<0>
J 0
(-3315 2785);
DISPLAY 0.659574 (-3315 2785);
PAINT MONO (-3315 2785);
DISPLAY INVISIBLE (-3315 2785);
FORCEPROP 1 LASTPIN (-3325 2775) BN 0
J 0
(-3337 2783);
DISPLAY 0.489362 (-3337 2783);
PAINT GREEN (-3337 2783);
FORCEPROP 2 LAST CDS_LIB mstr_standard
J 0
(-3275 2775);
DISPLAY 0.723404 (-3275 2775);
PAINT MONO (-3275 2775);
DISPLAY INVISIBLE (-3275 2775);
FORCEPROP 1 LAST BODY_TYPE PLUMBING
J 0
(-3275 2825);
DISPLAY 0.872340 (-3275 2825);
PAINT GREEN (-3275 2825);
DISPLAY INVISIBLE (-3275 2825);
FORCEPROP 1 LAST HDL_TAP TRUE
J 0
(-2950 2650);
DISPLAY 0.872340 (-2950 2650);
DISPLAY INVISIBLE (-2950 2650);
FORCEPROP 1 LAST PATH I235
J 0
(-3277 2775);
DISPLAY 0.872340 (-3277 2775);
PAINT GREEN (-3277 2775);
DISPLAY INVISIBLE (-3277 2775);
FORCEADD SCONN288_DDR506112002KQ..2
(-4425 3775);
FORCEPROP 1 LAST LOCATION J32
J 0
(-5025 5100);
DISPLAY 0.468085 (-5025 5100);
PAINT SKYBLUE (-5025 5100);
FORCEPROP 0 LAST $SEC 2
J 0
(-4875 5250);
DISPLAY 0.680851 (-4875 5250);
PAINT MONO (-4875 5250);
DISPLAY INVISIBLE (-4875 5250);
FORCEPROP 0 LAST CDS_SEC 2
J 0
(-4875 5250);
DISPLAY 1.021277 (-4875 5250);
DISPLAY INVISIBLE (-4875 5250);
FORCEPROP 0 LASTPIN (-3675 3825) $PN 12
J 0
(-3665 3835);
DISPLAY 0.680851 (-3665 3835);
PAINT MONO (-3665 3835);
FORCEPROP 0 LASTPIN (-3675 3875) $PN 11
J 0
(-3665 3885);
DISPLAY 0.680851 (-3665 3885);
PAINT MONO (-3665 3885);
FORCEPROP 0 LASTPIN (-3675 2775) $PN 105
J 0
(-3665 2785);
DISPLAY 0.680851 (-3665 2785);
PAINT MONO (-3665 2785);
FORCEPROP 0 LASTPIN (-3675 2825) $PN 104
J 0
(-3665 2835);
DISPLAY 0.680851 (-3665 2835);
PAINT MONO (-3665 2835);
FORCEPROP 0 LASTPIN (-3675 3925) $PN 23
J 0
(-3665 3935);
DISPLAY 0.680851 (-3665 3935);
PAINT MONO (-3665 3935);
FORCEPROP 0 LASTPIN (-3675 3975) $PN 22
J 0
(-3665 3985);
DISPLAY 0.680851 (-3665 3985);
PAINT MONO (-3665 3985);
FORCEPROP 0 LASTPIN (-3675 2875) $PN 116
J 0
(-3665 2885);
DISPLAY 0.680851 (-3665 2885);
PAINT MONO (-3665 2885);
FORCEPROP 0 LASTPIN (-3675 2925) $PN 115
J 0
(-3665 2935);
DISPLAY 0.680851 (-3665 2935);
PAINT MONO (-3665 2935);
FORCEPROP 0 LASTPIN (-3675 4025) $PN 34
J 0
(-3665 4035);
DISPLAY 0.680851 (-3665 4035);
PAINT MONO (-3665 4035);
FORCEPROP 0 LASTPIN (-3675 4075) $PN 33
J 0
(-3665 4085);
DISPLAY 0.680851 (-3665 4085);
PAINT MONO (-3665 4085);
FORCEPROP 0 LASTPIN (-3675 2975) $PN 127
J 0
(-3665 2985);
DISPLAY 0.680851 (-3665 2985);
PAINT MONO (-3665 2985);
FORCEPROP 0 LASTPIN (-3675 3025) $PN 126
J 0
(-3665 3035);
DISPLAY 0.680851 (-3665 3035);
PAINT MONO (-3665 3035);
FORCEPROP 0 LASTPIN (-3675 4125) $PN 45
J 0
(-3665 4135);
DISPLAY 0.680851 (-3665 4135);
PAINT MONO (-3665 4135);
FORCEPROP 0 LASTPIN (-3675 4175) $PN 44
J 0
(-3665 4185);
DISPLAY 0.680851 (-3665 4185);
PAINT MONO (-3665 4185);
FORCEPROP 0 LASTPIN (-3675 3075) $PN 138
J 0
(-3665 3085);
DISPLAY 0.680851 (-3665 3085);
PAINT MONO (-3665 3085);
FORCEPROP 0 LASTPIN (-3675 3125) $PN 137
J 0
(-3665 3135);
DISPLAY 0.680851 (-3665 3135);
PAINT MONO (-3665 3135);
FORCEPROP 0 LASTPIN (-3675 4225) $PN 56
J 0
(-3665 4235);
DISPLAY 0.680851 (-3665 4235);
PAINT MONO (-3665 4235);
FORCEPROP 0 LASTPIN (-3675 4275) $PN 55
J 0
(-3665 4285);
DISPLAY 0.680851 (-3665 4285);
PAINT MONO (-3665 4285);
FORCEPROP 0 LASTPIN (-3675 3175) $PN 238
J 0
(-3665 3185);
DISPLAY 0.680851 (-3665 3185);
PAINT MONO (-3665 3185);
FORCEPROP 0 LASTPIN (-3675 3225) $PN 239
J 0
(-3665 3235);
DISPLAY 0.680851 (-3665 3235);
PAINT MONO (-3665 3235);
FORCEPROP 0 LASTPIN (-3675 4325) $PN 156
J 0
(-3665 4335);
DISPLAY 0.680851 (-3665 4335);
PAINT MONO (-3665 4335);
FORCEPROP 0 LASTPIN (-3675 4375) $PN 157
J 0
(-3665 4385);
DISPLAY 0.680851 (-3665 4385);
PAINT MONO (-3665 4385);
FORCEPROP 0 LASTPIN (-3675 3275) $PN 249
J 0
(-3665 3285);
DISPLAY 0.680851 (-3665 3285);
PAINT MONO (-3665 3285);
FORCEPROP 0 LASTPIN (-3675 3325) $PN 250
J 0
(-3665 3335);
DISPLAY 0.680851 (-3665 3335);
PAINT MONO (-3665 3335);
FORCEPROP 0 LASTPIN (-3675 4425) $PN 167
J 0
(-3665 4435);
DISPLAY 0.680851 (-3665 4435);
PAINT MONO (-3665 4435);
FORCEPROP 0 LASTPIN (-3675 4475) $PN 168
J 0
(-3665 4485);
DISPLAY 0.680851 (-3665 4485);
PAINT MONO (-3665 4485);
FORCEPROP 0 LASTPIN (-3675 3375) $PN 260
J 0
(-3665 3385);
DISPLAY 0.680851 (-3665 3385);
PAINT MONO (-3665 3385);
FORCEPROP 0 LASTPIN (-3675 3425) $PN 261
J 0
(-3665 3435);
DISPLAY 0.680851 (-3665 3435);
PAINT MONO (-3665 3435);
FORCEPROP 0 LASTPIN (-3675 4525) $PN 178
J 0
(-3665 4535);
DISPLAY 0.680851 (-3665 4535);
PAINT MONO (-3665 4535);
FORCEPROP 0 LASTPIN (-3675 4575) $PN 179
J 0
(-3665 4585);
DISPLAY 0.680851 (-3665 4585);
PAINT MONO (-3665 4585);
FORCEPROP 0 LASTPIN (-3675 3475) $PN 271
J 0
(-3665 3485);
DISPLAY 0.680851 (-3665 3485);
PAINT MONO (-3665 3485);
FORCEPROP 0 LASTPIN (-3675 3525) $PN 272
J 0
(-3665 3535);
DISPLAY 0.680851 (-3665 3535);
PAINT MONO (-3665 3535);
FORCEPROP 0 LASTPIN (-3675 4625) $PN 189
J 0
(-3665 4635);
DISPLAY 0.680851 (-3665 4635);
PAINT MONO (-3665 4635);
FORCEPROP 0 LASTPIN (-3675 4675) $PN 190
J 0
(-3665 4685);
DISPLAY 0.680851 (-3665 4685);
PAINT MONO (-3665 4685);
FORCEPROP 0 LASTPIN (-3675 3575) $PN 282
J 0
(-3665 3585);
DISPLAY 0.680851 (-3665 3585);
PAINT MONO (-3665 3585);
FORCEPROP 0 LASTPIN (-3675 3625) $PN 283
J 0
(-3665 3635);
DISPLAY 0.680851 (-3665 3635);
PAINT MONO (-3665 3635);
FORCEPROP 0 LASTPIN (-3675 4725) $PN 200
J 0
(-3665 4735);
DISPLAY 0.680851 (-3665 4735);
PAINT MONO (-3665 4735);
FORCEPROP 0 LASTPIN (-3675 4775) $PN 201
J 0
(-3665 4785);
DISPLAY 0.680851 (-3665 4785);
PAINT MONO (-3665 4785);
FORCEPROP 0 LASTPIN (-3675 3675) $PN 94
J 0
(-3665 3685);
DISPLAY 0.680851 (-3665 3685);
PAINT MONO (-3665 3685);
FORCEPROP 0 LASTPIN (-3675 3725) $PN 93
J 0
(-3665 3735);
DISPLAY 0.680851 (-3665 3735);
PAINT MONO (-3665 3735);
FORCEPROP 1 LAST MATERIAL IO
J 0
(-5025 4950);
DISPLAY 0.468085 (-5025 4950);
PAINT SKYBLUE (-5025 4950);
FORCEPROP 2 LAST PART_TYPE SMLF
J 0
(-4875 5200);
DISPLAY 1.021277 (-4875 5200);
FORCEPROP 2 LAST VALUE SCONN288_DDR506112002KQ
J 0
(-4875 5150);
DISPLAY 0.489362 (-4875 5150);
PAINT SKYBLUE (-4875 5150);
FORCEPROP 1 LAST PART_NUMBER DFHST8FS479
J 0
(-5025 5025);
DISPLAY 0.468085 (-5025 5025);
PAINT SKYBLUE (-5025 5025);
FORCEPROP 1 LAST CDS_LMAN_SYM_OUTLINE -600,1150,600,-1150
J 0
(-4425 3775);
DISPLAY 0.468085 (-4425 3775);
PAINT GREEN (-4425 3775);
DISPLAY INVISIBLE (-4425 3775);
FORCEPROP 1 LAST PATH I236
J 0
(-4425 3775);
DISPLAY 0.723404 (-4425 3775);
PAINT GREEN (-4425 3775);
DISPLAY INVISIBLE (-4425 3775);
FORCEPROP 1 LAST NEEDS_NO_SIZE TRUE
J 0
(-4425 3775);
DISPLAY 0.723404 (-4425 3775);
PAINT GREEN (-4425 3775);
DISPLAY INVISIBLE (-4425 3775);
FORCEPROP 2 LAST CDS_LIB pure_quanta
J 0
(-4425 3775);
DISPLAY INVISIBLE (-4425 3775);
FORCEADD GND..1
(-2875 5825);
FORCEPROP 3 LASTPIN (-2875 5875) SIG_NAME GND\g
J 0
(-2865 5885);
DISPLAY 0.659574 (-2865 5885);
PAINT MONO (-2865 5885);
DISPLAY INVISIBLE (-2865 5885);
FORCEPROP 2 LAST CDS_LIB pure_quanta_power
J 0
(-2875 5825);
DISPLAY INVISIBLE (-2875 5825);
FORCEPROP 2 LAST BOM_COST MEM
J 0
(-2850 5950);
DISPLAY 0.659574 (-2850 5950);
DISPLAY INVISIBLE (-2850 5950);
FORCEPROP 1 LAST SIZE 1B
J 0
(-2800 5775);
DISPLAY 0.723404 (-2800 5775);
PAINT GREEN (-2800 5775);
DISPLAY INVISIBLE (-2800 5775);
FORCEPROP 1 LAST PATH I237
J 0
(-2800 5825);
DISPLAY 0.872340 (-2800 5825);
PAINT AQUA (-2800 5825);
DISPLAY INVISIBLE (-2800 5825);
FORCEPROP 2 LAST ROOM MEM_EFGH_DECOUPLING_CAPS
J 0
(-2850 5900);
DISPLAY 0.659574 (-2850 5900);
PAINT RED (-2850 5900);
DISPLAY INVISIBLE (-2850 5900);
FORCEPROP 1 LAST HDL_POWER GND
J 0
(-2875 5975);
DISPLAY 0.723404 (-2875 5975);
PAINT GREEN (-2875 5975);
DISPLAY INVISIBLE (-2875 5975);
FORCEADD Q_CAP..1
R 2
(-2875 6175);
FORCEPROP 1 LAST LOCATION C183
J 2
(-2925 6275);
DISPLAY 0.489362 (-2925 6275);
PAINT SKYBLUE (-2925 6275);
FORCEPROP 0 LAST $SEC 1
J 0
(-2925 6325);
DISPLAY 0.680851 (-2925 6325);
PAINT MONO (-2925 6325);
DISPLAY INVISIBLE (-2925 6325);
FORCEPROP 0 LAST CDS_SEC 1
J 0
(-2925 6325);
DISPLAY 0.680851 (-2925 6325);
DISPLAY INVISIBLE (-2925 6325);
FORCEPROP 1 LASTPIN (-2875 6275) $PN 1
J 2
(-2885 6255);
DISPLAY 0.489362 (-2885 6255);
PAINT MONO (-2885 6255);
FORCEPROP 1 LASTPIN (-2875 6075) $PN 2
J 2
(-2885 6055);
DISPLAY 0.489362 (-2885 6055);
PAINT MONO (-2885 6055);
FORCEPROP 1 LAST MATERIAL X6S
J 2
(-2925 6075);
DISPLAY 0.489362 (-2925 6075);
PAINT SKYBLUE (-2925 6075);
FORCEPROP 1 LAST TOLERANCE 10%
J 2
(-2925 6125);
DISPLAY 0.489362 (-2925 6125);
PAINT SKYBLUE (-2925 6125);
FORCEPROP 1 LAST VALUE 10UF
J 2
(-2925 6225);
DISPLAY 0.489362 (-2925 6225);
PAINT SKYBLUE (-2925 6225);
FORCEPROP 1 LAST VOLTAGE 25V
J 2
(-2925 6175);
DISPLAY 0.489362 (-2925 6175);
PAINT SKYBLUE (-2925 6175);
FORCEPROP 1 LAST PACK_TYPE C0805
J 2
(-2925 5975);
DISPLAY 0.489362 (-2925 5975);
PAINT SKYBLUE (-2925 5975);
FORCEPROP 1 LAST PART_NUMBER CH6104KEA00
J 2
(-2925 6025);
DISPLAY 0.489362 (-2925 6025);
PAINT SKYBLUE (-2925 6025);
FORCEPROP 0 LAST BOM_COST MEM
J 2
(-2930 6320);
DISPLAY 0.595745 (-2930 6320);
PAINT MONO (-2930 6320);
DISPLAY INVISIBLE (-2930 6320);
FORCEPROP 2 LAST CDS_LIB pure_quanta
J 0
(-2875 6175);
DISPLAY INVISIBLE (-2875 6175);
FORCEPROP 1 LAST PATH I238
J 2
(-2925 6325);
DISPLAY 0.978723 (-2925 6325);
PAINT WHITE (-2925 6325);
DISPLAY INVISIBLE (-2925 6325);
FORCEPROP 0 LAST ROOM MEM_CH_A_CPU0_DIMM1
J 2
(-2930 6320);
DISPLAY 0.595745 (-2930 6320);
PAINT RED (-2930 6320);
DISPLAY INVISIBLE (-2930 6320);
FORCEADD Q_CAP..1
R 2
(-2300 6175);
FORCEPROP 1 LAST LOCATION C509
J 2
(-2350 6275);
DISPLAY 0.489362 (-2350 6275);
PAINT SKYBLUE (-2350 6275);
FORCEPROP 0 LAST $SEC 1
J 0
(-2350 6325);
DISPLAY 0.680851 (-2350 6325);
PAINT MONO (-2350 6325);
DISPLAY INVISIBLE (-2350 6325);
FORCEPROP 0 LAST CDS_SEC 1
J 0
(-2350 6325);
DISPLAY 0.680851 (-2350 6325);
DISPLAY INVISIBLE (-2350 6325);
FORCEPROP 1 LASTPIN (-2300 6275) $PN 1
J 2
(-2310 6255);
DISPLAY 0.489362 (-2310 6255);
PAINT MONO (-2310 6255);
FORCEPROP 1 LASTPIN (-2300 6075) $PN 2
J 2
(-2310 6055);
DISPLAY 0.489362 (-2310 6055);
PAINT MONO (-2310 6055);
FORCEPROP 1 LAST MATERIAL X6S
J 2
(-2350 6075);
DISPLAY 0.489362 (-2350 6075);
PAINT SKYBLUE (-2350 6075);
FORCEPROP 1 LAST TOLERANCE 10%
J 2
(-2350 6125);
DISPLAY 0.489362 (-2350 6125);
PAINT SKYBLUE (-2350 6125);
FORCEPROP 1 LAST VALUE 10UF
J 2
(-2350 6225);
DISPLAY 0.489362 (-2350 6225);
PAINT SKYBLUE (-2350 6225);
FORCEPROP 1 LAST PART_NUMBER CH6104KEA00
J 2
(-2350 6025);
DISPLAY 0.489362 (-2350 6025);
PAINT SKYBLUE (-2350 6025);
FORCEPROP 1 LAST VOLTAGE 25V
J 2
(-2350 6175);
DISPLAY 0.489362 (-2350 6175);
PAINT SKYBLUE (-2350 6175);
FORCEPROP 1 LAST PACK_TYPE C0805
J 2
(-2350 5975);
DISPLAY 0.489362 (-2350 5975);
PAINT SKYBLUE (-2350 5975);
FORCEPROP 0 LAST BOM_COST MEM
J 2
(-2355 6320);
DISPLAY 0.595745 (-2355 6320);
PAINT MONO (-2355 6320);
DISPLAY INVISIBLE (-2355 6320);
FORCEPROP 2 LAST CDS_LIB pure_quanta
J 0
(-2300 6175);
DISPLAY INVISIBLE (-2300 6175);
FORCEPROP 1 LAST PATH I239
J 2
(-2350 6325);
DISPLAY 0.978723 (-2350 6325);
PAINT WHITE (-2350 6325);
DISPLAY INVISIBLE (-2350 6325);
FORCEPROP 0 LAST ROOM MEM_CH_A_CPU0_DIMM1
J 2
(-2355 6320);
DISPLAY 0.595745 (-2355 6320);
PAINT RED (-2355 6320);
DISPLAY INVISIBLE (-2355 6320);
FORCEADD TAP..1
R 2
(-7875 4150);
FORCEPROP 3 LASTPIN (-7825 4150) SIG_NAME M_E_CPU1_SA_CB<5>
J 0
(-7815 4160);
DISPLAY 0.659574 (-7815 4160);
PAINT MONO (-7815 4160);
DISPLAY INVISIBLE (-7815 4160);
FORCEPROP 1 LASTPIN (-7825 4150) BN 5
J 2
(-7813 4158);
DISPLAY 0.489362 (-7813 4158);
PAINT GREEN (-7813 4158);
FORCEPROP 2 LAST CDS_LIB mstr_standard
J 0
(-7875 4150);
DISPLAY 0.723404 (-7875 4150);
PAINT MONO (-7875 4150);
DISPLAY INVISIBLE (-7875 4150);
FORCEPROP 1 LAST BODY_TYPE PLUMBING
J 2
(-7875 4200);
DISPLAY 0.872340 (-7875 4200);
PAINT GREEN (-7875 4200);
DISPLAY INVISIBLE (-7875 4200);
FORCEPROP 1 LAST HDL_TAP TRUE
J 2
(-8200 4025);
DISPLAY 0.872340 (-8200 4025);
DISPLAY INVISIBLE (-8200 4025);
FORCEPROP 1 LAST PATH I24
J 2
(-7873 4150);
DISPLAY 0.872340 (-7873 4150);
PAINT GREEN (-7873 4150);
DISPLAY INVISIBLE (-7873 4150);
FORCEADD UNIVERSAL_POWER..1
(-2875 6500);
FORCEPROP 3 LASTPIN (-2875 6450) SIG_NAME P12V_MEM_2\g
J 0
(-2865 6460);
DISPLAY 0.659574 (-2865 6460);
PAINT MONO (-2865 6460);
DISPLAY INVISIBLE (-2865 6460);
FORCEPROP 1 LAST HDL_POWER P12V_MEM_2
J 1
(-2875 6550);
DISPLAY 0.489362 (-2875 6550);
PAINT GREEN (-2875 6550);
FORCEPROP 2 LAST CDS_LIB pure_quanta_power
J 0
(-2875 6500);
DISPLAY INVISIBLE (-2875 6500);
FORCEPROP 1 LAST PATH I240
J 0
(-2825 6525);
DISPLAY 0.872340 (-2825 6525);
PAINT AQUA (-2825 6525);
DISPLAY INVISIBLE (-2825 6525);
FORCEADD OFFPAGE..1
(-8475 2925);
FORCEPROP 2 LAST $XR5 102 
J 0
(-9267 2925);
DISPLAY 0.638298 (-9267 2925);
PAINT MONO (-9267 2925);
FORCEPROP 2 LAST $XR4 100 
J 0
(-9147 2925);
DISPLAY 0.638298 (-9147 2925);
PAINT MONO (-9147 2925);
FORCEPROP 2 LAST $XR3 99 
J 0
(-9027 2925);
DISPLAY 0.638298 (-9027 2925);
PAINT MONO (-9027 2925);
FORCEPROP 2 LAST $XR2 98 
J 0
(-8937 2925);
DISPLAY 0.638298 (-8937 2925);
PAINT MONO (-8937 2925);
FORCEPROP 2 LAST $XR1 97 
J 0
(-8847 2925);
DISPLAY 0.638298 (-8847 2925);
PAINT MONO (-8847 2925);
FORCEPROP 2 LAST $XR0 136 
J 0
(-8757 2925);
DISPLAY 0.638298 (-8757 2925);
PAINT MONO (-8757 2925);
FORCEPROP 2 LAST CDS_LIB mstr_standard
J 0
(-8475 2925);
DISPLAY 0.808511 (-8475 2925);
DISPLAY INVISIBLE (-8475 2925);
FORCEPROP 1 LAST OFFPAGE TRUE
J 0
(-8150 2800);
DISPLAY 0.872340 (-8150 2800);
PAINT GREEN (-8150 2800);
DISPLAY INVISIBLE (-8150 2800);
FORCEPROP 1 LAST COMMENT_BODY TRUE
J 0
(-8350 2825);
DISPLAY 0.872340 (-8350 2825);
PAINT GREEN (-8350 2825);
DISPLAY INVISIBLE (-8350 2825);
FORCEPROP 2 LAST PATH I241
J 0
(-8750 2975);
DISPLAY 0.680851 (-8750 2975);
DISPLAY INVISIBLE (-8750 2975);
FORCEADD Q_RES..1
(-7925 2925);
FORCEPROP 1 LAST $LOCATION R1584
J 0
(-7975 2950);
DISPLAY 0.510638 (-7975 2950);
PAINT SKYBLUE (-7975 2950);
FORCEPROP 0 LAST CDS_LOCATION R1584
J 0
(-7975 3025);
DISPLAY 0.680851 (-7975 3025);
DISPLAY INVISIBLE (-7975 3025);
FORCEPROP 0 LAST $SEC 1
J 0
(-7975 3025);
DISPLAY 0.680851 (-7975 3025);
PAINT MONO (-7975 3025);
DISPLAY INVISIBLE (-7975 3025);
FORCEPROP 0 LAST CDS_SEC 1
J 0
(-7975 3025);
DISPLAY 0.680851 (-7975 3025);
DISPLAY INVISIBLE (-7975 3025);
FORCEPROP 1 LASTPIN (-8025 2925) $PN 1
J 0
(-8013 2937);
DISPLAY 0.787234 (-8013 2937);
PAINT MONO (-8013 2937);
FORCEPROP 1 LASTPIN (-7825 2925) $PN 2
J 0
(-7863 2937);
DISPLAY 0.787234 (-7863 2937);
PAINT MONO (-7863 2937);
FORCEPROP 1 LAST VALUE 49.9
J 2
(-7775 2975);
DISPLAY 0.510638 (-7775 2975);
PAINT SKYBLUE (-7775 2975);
FORCEPROP 2 LAST CDS_LIB pure_quanta
J 0
(-7925 2925);
DISPLAY INVISIBLE (-7925 2925);
FORCEPROP 1 LAST PATH I242
J 0
(-7975 3075);
DISPLAY 0.978723 (-7975 3075);
PAINT WHITE (-7975 3075);
DISPLAY INVISIBLE (-7975 3075);
FORCEPROP 1 LAST PART_NUMBER CS04992FB07
J 0
(-7975 3025);
DISPLAY 0.978723 (-7975 3025);
DISPLAY INVISIBLE (-7975 3025);
FORCEPROP 1 LAST TOLERANCE 1%
J 0
(-7925 2825);
DISPLAY 0.978723 (-7925 2825);
DISPLAY INVISIBLE (-7925 2825);
FORCEPROP 1 LAST WATTAGE 1/16W
J 2
(-7950 2775);
DISPLAY 0.978723 (-7950 2775);
DISPLAY INVISIBLE (-7950 2775);
FORCEPROP 1 LAST PACK_TYPE 0402LF
J 0
(-7675 2775);
DISPLAY 0.978723 (-7675 2775);
DISPLAY INVISIBLE (-7675 2775);
FORCEPROP 1 LAST MATERIAL CHIP
J 0
(-7925 2775);
DISPLAY 0.978723 (-7925 2775);
DISPLAY INVISIBLE (-7925 2775);
FORCEADD OFFPAGE..6
(-8475 4300);
FORCEPROP 2 LAST $XR0 41 
J 0
(-8754 4300);
DISPLAY 0.638298 (-8754 4300);
PAINT MONO (-8754 4300);
FORCEPROP 2 LAST PATH I25
J 0
(-8750 4350);
DISPLAY 1.021277 (-8750 4350);
DISPLAY INVISIBLE (-8750 4350);
FORCEPROP 1 LAST COMMENT_BODY TRUE
J 0
(-8375 4225);
DISPLAY 0.872340 (-8375 4225);
PAINT GREEN (-8375 4225);
DISPLAY INVISIBLE (-8375 4225);
FORCEPROP 1 LAST OFFPAGE TRUE
J 0
(-8150 4175);
DISPLAY 0.872340 (-8150 4175);
PAINT GREEN (-8150 4175);
DISPLAY INVISIBLE (-8150 4175);
FORCEPROP 2 LAST CDS_LIB mstr_standard
J 0
(-8475 4300);
DISPLAY 0.723404 (-8475 4300);
PAINT MONO (-8475 4300);
DISPLAY INVISIBLE (-8475 4300);
FORCEADD OFFPAGE..1
(-8475 4400);
FORCEPROP 2 LAST $XR0 41 
J 0
(-8726 4400);
DISPLAY 0.638298 (-8726 4400);
PAINT MONO (-8726 4400);
FORCEPROP 2 LAST PATH I26
J 0
(-8725 4450);
DISPLAY 1.021277 (-8725 4450);
DISPLAY INVISIBLE (-8725 4450);
FORCEPROP 1 LAST COMMENT_BODY TRUE
J 0
(-8350 4300);
DISPLAY 0.872340 (-8350 4300);
PAINT GREEN (-8350 4300);
DISPLAY INVISIBLE (-8350 4300);
FORCEPROP 1 LAST OFFPAGE TRUE
J 0
(-8150 4275);
DISPLAY 0.872340 (-8150 4275);
PAINT GREEN (-8150 4275);
DISPLAY INVISIBLE (-8150 4275);
FORCEPROP 2 LAST CDS_LIB mstr_standard
J 0
(-8475 4400);
DISPLAY 0.723404 (-8475 4400);
PAINT MONO (-8475 4400);
DISPLAY INVISIBLE (-8475 4400);
FORCEADD OFFPAGE..1
(-8475 4350);
FORCEPROP 2 LAST $XR0 41 
J 0
(-8726 4350);
DISPLAY 0.638298 (-8726 4350);
PAINT MONO (-8726 4350);
FORCEPROP 2 LAST PATH I27
J 0
(-8725 4400);
DISPLAY 1.021277 (-8725 4400);
DISPLAY INVISIBLE (-8725 4400);
FORCEPROP 1 LAST COMMENT_BODY TRUE
J 0
(-8350 4250);
DISPLAY 0.872340 (-8350 4250);
PAINT GREEN (-8350 4250);
DISPLAY INVISIBLE (-8350 4250);
FORCEPROP 1 LAST OFFPAGE TRUE
J 0
(-8150 4225);
DISPLAY 0.872340 (-8150 4225);
PAINT GREEN (-8150 4225);
DISPLAY INVISIBLE (-8150 4225);
FORCEPROP 2 LAST CDS_LIB mstr_standard
J 0
(-8475 4350);
DISPLAY 0.808511 (-8475 4350);
DISPLAY INVISIBLE (-8475 4350);
FORCEADD OFFPAGE..1
(-8475 4500);
FORCEPROP 2 LAST $XR0 41 
J 0
(-8726 4500);
DISPLAY 0.638298 (-8726 4500);
PAINT MONO (-8726 4500);
FORCEPROP 2 LAST PATH I28
J 0
(-8725 4550);
DISPLAY 1.021277 (-8725 4550);
DISPLAY INVISIBLE (-8725 4550);
FORCEPROP 1 LAST COMMENT_BODY TRUE
J 0
(-8350 4400);
DISPLAY 0.872340 (-8350 4400);
PAINT GREEN (-8350 4400);
DISPLAY INVISIBLE (-8350 4400);
FORCEPROP 1 LAST OFFPAGE TRUE
J 0
(-8150 4375);
DISPLAY 0.872340 (-8150 4375);
PAINT GREEN (-8150 4375);
DISPLAY INVISIBLE (-8150 4375);
FORCEPROP 2 LAST CDS_LIB mstr_standard
J 0
(-8475 4500);
DISPLAY 0.808511 (-8475 4500);
DISPLAY INVISIBLE (-8475 4500);
FORCEADD OFFPAGE..1
(-8475 4550);
FORCEPROP 2 LAST $XR0 41 
J 0
(-8726 4550);
DISPLAY 0.638298 (-8726 4550);
PAINT MONO (-8726 4550);
FORCEPROP 2 LAST PATH I29
J 0
(-8725 4600);
DISPLAY 1.021277 (-8725 4600);
DISPLAY INVISIBLE (-8725 4600);
FORCEPROP 1 LAST COMMENT_BODY TRUE
J 0
(-8350 4450);
DISPLAY 0.872340 (-8350 4450);
PAINT GREEN (-8350 4450);
DISPLAY INVISIBLE (-8350 4450);
FORCEPROP 1 LAST OFFPAGE TRUE
J 0
(-8150 4425);
DISPLAY 0.872340 (-8150 4425);
PAINT GREEN (-8150 4425);
DISPLAY INVISIBLE (-8150 4425);
FORCEPROP 2 LAST CDS_LIB mstr_standard
J 0
(-8475 4550);
DISPLAY 0.723404 (-8475 4550);
PAINT MONO (-8475 4550);
DISPLAY INVISIBLE (-8475 4550);
FORCEADD OFFPAGE..5
(-8475 2200);
FORCEPROP 2 LAST $XR0 41 
J 0
(-8699 2200);
DISPLAY 0.638298 (-8699 2200);
PAINT MONO (-8699 2200);
FORCEPROP 2 LAST PATH I3
J 0
(-8725 2250);
DISPLAY 1.021277 (-8725 2250);
DISPLAY INVISIBLE (-8725 2250);
FORCEPROP 1 LAST COMMENT_BODY TRUE
J 0
(-8375 2125);
DISPLAY 0.872340 (-8375 2125);
PAINT GREEN (-8375 2125);
DISPLAY INVISIBLE (-8375 2125);
FORCEPROP 1 LAST OFFPAGE TRUE
J 0
(-8150 2075);
DISPLAY 0.872340 (-8150 2075);
PAINT GREEN (-8150 2075);
DISPLAY INVISIBLE (-8150 2075);
FORCEPROP 2 LAST CDS_LIB mstr_standard
J 0
(-8475 2200);
DISPLAY 0.808511 (-8475 2200);
DISPLAY INVISIBLE (-8475 2200);
FORCEADD OFFPAGE..1
(-8475 4650);
FORCEPROP 2 LAST $XR0 41 
J 0
(-8726 4650);
DISPLAY 0.638298 (-8726 4650);
PAINT MONO (-8726 4650);
FORCEPROP 2 LAST PATH I30
J 0
(-8725 4700);
DISPLAY 1.021277 (-8725 4700);
DISPLAY INVISIBLE (-8725 4700);
FORCEPROP 1 LAST COMMENT_BODY TRUE
J 0
(-8350 4550);
DISPLAY 0.872340 (-8350 4550);
PAINT GREEN (-8350 4550);
DISPLAY INVISIBLE (-8350 4550);
FORCEPROP 1 LAST OFFPAGE TRUE
J 0
(-8150 4525);
DISPLAY 0.872340 (-8150 4525);
PAINT GREEN (-8150 4525);
DISPLAY INVISIBLE (-8150 4525);
FORCEPROP 2 LAST CDS_LIB mstr_standard
J 0
(-8475 4650);
DISPLAY 0.808511 (-8475 4650);
DISPLAY INVISIBLE (-8475 4650);
FORCEADD OFFPAGE..1
(-8475 4700);
FORCEPROP 2 LAST $XR0 41 
J 0
(-8726 4700);
DISPLAY 0.638298 (-8726 4700);
PAINT MONO (-8726 4700);
FORCEPROP 2 LAST PATH I31
J 0
(-8725 4750);
DISPLAY 1.021277 (-8725 4750);
DISPLAY INVISIBLE (-8725 4750);
FORCEPROP 1 LAST COMMENT_BODY TRUE
J 0
(-8350 4600);
DISPLAY 0.872340 (-8350 4600);
PAINT GREEN (-8350 4600);
DISPLAY INVISIBLE (-8350 4600);
FORCEPROP 1 LAST OFFPAGE TRUE
J 0
(-8150 4575);
DISPLAY 0.872340 (-8150 4575);
PAINT GREEN (-8150 4575);
DISPLAY INVISIBLE (-8150 4575);
FORCEPROP 2 LAST CDS_LIB mstr_standard
J 0
(-8475 4700);
DISPLAY 0.723404 (-8475 4700);
PAINT MONO (-8475 4700);
DISPLAY INVISIBLE (-8475 4700);
FORCEADD OFFPAGE..1
(-8475 4800);
FORCEPROP 2 LAST $XR0 41 
J 0
(-8726 4800);
DISPLAY 0.638298 (-8726 4800);
PAINT MONO (-8726 4800);
FORCEPROP 2 LAST PATH I32
J 0
(-8725 4850);
DISPLAY 1.021277 (-8725 4850);
DISPLAY INVISIBLE (-8725 4850);
FORCEPROP 1 LAST COMMENT_BODY TRUE
J 0
(-8350 4700);
DISPLAY 0.872340 (-8350 4700);
PAINT GREEN (-8350 4700);
DISPLAY INVISIBLE (-8350 4700);
FORCEPROP 1 LAST OFFPAGE TRUE
J 0
(-8150 4675);
DISPLAY 0.872340 (-8150 4675);
PAINT GREEN (-8150 4675);
DISPLAY INVISIBLE (-8150 4675);
FORCEPROP 2 LAST CDS_LIB mstr_standard
J 0
(-8475 4800);
DISPLAY 0.808511 (-8475 4800);
DISPLAY INVISIBLE (-8475 4800);
FORCEADD OFFPAGE..1
(-8475 4850);
FORCEPROP 2 LAST $XR0 41 
J 0
(-8726 4850);
DISPLAY 0.638298 (-8726 4850);
PAINT MONO (-8726 4850);
FORCEPROP 2 LAST PATH I33
J 0
(-8725 4900);
DISPLAY 1.021277 (-8725 4900);
DISPLAY INVISIBLE (-8725 4900);
FORCEPROP 1 LAST COMMENT_BODY TRUE
J 0
(-8350 4750);
DISPLAY 0.872340 (-8350 4750);
PAINT GREEN (-8350 4750);
DISPLAY INVISIBLE (-8350 4750);
FORCEPROP 1 LAST OFFPAGE TRUE
J 0
(-8150 4725);
DISPLAY 0.872340 (-8150 4725);
PAINT GREEN (-8150 4725);
DISPLAY INVISIBLE (-8150 4725);
FORCEPROP 2 LAST CDS_LIB mstr_standard
J 0
(-8475 4850);
DISPLAY 0.723404 (-8475 4850);
PAINT MONO (-8475 4850);
DISPLAY INVISIBLE (-8475 4850);
FORCEADD TAP..1
R 2
(-7875 4200);
FORCEPROP 3 LASTPIN (-7825 4200) SIG_NAME M_E_CPU1_SA_CB<6>
J 0
(-7815 4210);
DISPLAY 0.659574 (-7815 4210);
PAINT MONO (-7815 4210);
DISPLAY INVISIBLE (-7815 4210);
FORCEPROP 1 LASTPIN (-7825 4200) BN 6
J 2
(-7813 4208);
DISPLAY 0.489362 (-7813 4208);
PAINT GREEN (-7813 4208);
FORCEPROP 2 LAST CDS_LIB mstr_standard
J 0
(-7875 4200);
DISPLAY 0.723404 (-7875 4200);
PAINT MONO (-7875 4200);
DISPLAY INVISIBLE (-7875 4200);
FORCEPROP 1 LAST BODY_TYPE PLUMBING
J 2
(-7875 4250);
DISPLAY 0.872340 (-7875 4250);
PAINT GREEN (-7875 4250);
DISPLAY INVISIBLE (-7875 4250);
FORCEPROP 1 LAST HDL_TAP TRUE
J 2
(-8200 4075);
DISPLAY 0.872340 (-8200 4075);
DISPLAY INVISIBLE (-8200 4075);
FORCEPROP 1 LAST PATH I34
J 2
(-7873 4200);
DISPLAY 0.872340 (-7873 4200);
PAINT GREEN (-7873 4200);
DISPLAY INVISIBLE (-7873 4200);
FORCEADD TAP..1
R 2
(-7875 4250);
FORCEPROP 3 LASTPIN (-7825 4250) SIG_NAME M_E_CPU1_SA_CB<7>
J 0
(-7815 4260);
DISPLAY 0.659574 (-7815 4260);
PAINT MONO (-7815 4260);
DISPLAY INVISIBLE (-7815 4260);
FORCEPROP 1 LASTPIN (-7825 4250) BN 7
J 2
(-7813 4258);
DISPLAY 0.489362 (-7813 4258);
PAINT GREEN (-7813 4258);
FORCEPROP 2 LAST CDS_LIB mstr_standard
J 0
(-7875 4250);
DISPLAY 0.723404 (-7875 4250);
PAINT MONO (-7875 4250);
DISPLAY INVISIBLE (-7875 4250);
FORCEPROP 1 LAST BODY_TYPE PLUMBING
J 2
(-7875 4300);
DISPLAY 0.872340 (-7875 4300);
PAINT GREEN (-7875 4300);
DISPLAY INVISIBLE (-7875 4300);
FORCEPROP 1 LAST HDL_TAP TRUE
J 2
(-8200 4125);
DISPLAY 0.872340 (-8200 4125);
DISPLAY INVISIBLE (-8200 4125);
FORCEPROP 1 LAST PATH I35
J 2
(-7873 4250);
DISPLAY 0.872340 (-7873 4250);
PAINT GREEN (-7873 4250);
DISPLAY INVISIBLE (-7873 4250);
FORCEADD TAP..1
R 2
(-7875 5000);
FORCEPROP 3 LASTPIN (-7825 5000) SIG_NAME M_E_CPU1_SB_CA<1>
J 0
(-7815 5010);
DISPLAY 0.659574 (-7815 5010);
PAINT MONO (-7815 5010);
DISPLAY INVISIBLE (-7815 5010);
FORCEPROP 1 LASTPIN (-7825 5000) BN 1
J 2
(-7813 5008);
DISPLAY 0.489362 (-7813 5008);
PAINT GREEN (-7813 5008);
FORCEPROP 2 LAST CDS_LIB mstr_standard
J 0
(-7875 5000);
DISPLAY 0.723404 (-7875 5000);
PAINT MONO (-7875 5000);
DISPLAY INVISIBLE (-7875 5000);
FORCEPROP 1 LAST BODY_TYPE PLUMBING
J 2
(-7875 5050);
DISPLAY 0.872340 (-7875 5050);
PAINT GREEN (-7875 5050);
DISPLAY INVISIBLE (-7875 5050);
FORCEPROP 1 LAST HDL_TAP TRUE
J 2
(-8200 4875);
DISPLAY 0.872340 (-8200 4875);
DISPLAY INVISIBLE (-8200 4875);
FORCEPROP 1 LAST PATH I36
J 2
(-7873 5000);
DISPLAY 0.872340 (-7873 5000);
PAINT GREEN (-7873 5000);
DISPLAY INVISIBLE (-7873 5000);
FORCEADD TAP..1
R 2
(-7875 4950);
FORCEPROP 3 LASTPIN (-7825 4950) SIG_NAME M_E_CPU1_SB_CA<0>
J 0
(-7815 4960);
DISPLAY 0.659574 (-7815 4960);
PAINT MONO (-7815 4960);
DISPLAY INVISIBLE (-7815 4960);
FORCEPROP 1 LASTPIN (-7825 4950) BN 0
J 2
(-7813 4958);
DISPLAY 0.489362 (-7813 4958);
PAINT GREEN (-7813 4958);
FORCEPROP 2 LAST CDS_LIB mstr_standard
J 0
(-7875 4950);
DISPLAY 0.723404 (-7875 4950);
PAINT MONO (-7875 4950);
DISPLAY INVISIBLE (-7875 4950);
FORCEPROP 1 LAST BODY_TYPE PLUMBING
J 2
(-7875 5000);
DISPLAY 0.872340 (-7875 5000);
PAINT GREEN (-7875 5000);
DISPLAY INVISIBLE (-7875 5000);
FORCEPROP 1 LAST HDL_TAP TRUE
J 2
(-8200 4825);
DISPLAY 0.872340 (-8200 4825);
DISPLAY INVISIBLE (-8200 4825);
FORCEPROP 1 LAST PATH I37
J 2
(-7873 4950);
DISPLAY 0.872340 (-7873 4950);
PAINT GREEN (-7873 4950);
DISPLAY INVISIBLE (-7873 4950);
FORCEADD TAP..1
R 2
(-7875 5050);
FORCEPROP 3 LASTPIN (-7825 5050) SIG_NAME M_E_CPU1_SB_CA<2>
J 0
(-7815 5060);
DISPLAY 0.659574 (-7815 5060);
PAINT MONO (-7815 5060);
DISPLAY INVISIBLE (-7815 5060);
FORCEPROP 1 LASTPIN (-7825 5050) BN 2
J 2
(-7813 5058);
DISPLAY 0.489362 (-7813 5058);
PAINT GREEN (-7813 5058);
FORCEPROP 2 LAST CDS_LIB mstr_standard
J 0
(-7875 5050);
DISPLAY 0.723404 (-7875 5050);
PAINT MONO (-7875 5050);
DISPLAY INVISIBLE (-7875 5050);
FORCEPROP 1 LAST BODY_TYPE PLUMBING
J 2
(-7875 5100);
DISPLAY 0.872340 (-7875 5100);
PAINT GREEN (-7875 5100);
DISPLAY INVISIBLE (-7875 5100);
FORCEPROP 1 LAST HDL_TAP TRUE
J 2
(-8200 4925);
DISPLAY 0.872340 (-8200 4925);
DISPLAY INVISIBLE (-8200 4925);
FORCEPROP 1 LAST PATH I38
J 2
(-7873 5050);
DISPLAY 0.872340 (-7873 5050);
PAINT GREEN (-7873 5050);
DISPLAY INVISIBLE (-7873 5050);
FORCEADD TAP..1
R 2
(-7875 5100);
FORCEPROP 3 LASTPIN (-7825 5100) SIG_NAME M_E_CPU1_SB_CA<3>
J 0
(-7815 5110);
DISPLAY 0.659574 (-7815 5110);
PAINT MONO (-7815 5110);
DISPLAY INVISIBLE (-7815 5110);
FORCEPROP 1 LASTPIN (-7825 5100) BN 3
J 2
(-7813 5108);
DISPLAY 0.489362 (-7813 5108);
PAINT GREEN (-7813 5108);
FORCEPROP 2 LAST CDS_LIB mstr_standard
J 0
(-7875 5100);
DISPLAY 0.723404 (-7875 5100);
PAINT MONO (-7875 5100);
DISPLAY INVISIBLE (-7875 5100);
FORCEPROP 1 LAST BODY_TYPE PLUMBING
J 2
(-7875 5150);
DISPLAY 0.872340 (-7875 5150);
PAINT GREEN (-7875 5150);
DISPLAY INVISIBLE (-7875 5150);
FORCEPROP 1 LAST HDL_TAP TRUE
J 2
(-8200 4975);
DISPLAY 0.872340 (-8200 4975);
DISPLAY INVISIBLE (-8200 4975);
FORCEPROP 1 LAST PATH I39
J 2
(-7873 5100);
DISPLAY 0.872340 (-7873 5100);
PAINT GREEN (-7873 5100);
DISPLAY INVISIBLE (-7873 5100);
FORCEADD TAP..1
R 2
(-7875 5150);
FORCEPROP 3 LASTPIN (-7825 5150) SIG_NAME M_E_CPU1_SB_CA<4>
J 0
(-7815 5160);
DISPLAY 0.659574 (-7815 5160);
PAINT MONO (-7815 5160);
DISPLAY INVISIBLE (-7815 5160);
FORCEPROP 1 LASTPIN (-7825 5150) BN 4
J 2
(-7813 5158);
DISPLAY 0.489362 (-7813 5158);
PAINT GREEN (-7813 5158);
FORCEPROP 2 LAST CDS_LIB mstr_standard
J 0
(-7875 5150);
DISPLAY 0.723404 (-7875 5150);
PAINT MONO (-7875 5150);
DISPLAY INVISIBLE (-7875 5150);
FORCEPROP 1 LAST BODY_TYPE PLUMBING
J 2
(-7875 5200);
DISPLAY 0.872340 (-7875 5200);
PAINT GREEN (-7875 5200);
DISPLAY INVISIBLE (-7875 5200);
FORCEPROP 1 LAST HDL_TAP TRUE
J 2
(-8200 5025);
DISPLAY 0.872340 (-8200 5025);
DISPLAY INVISIBLE (-8200 5025);
FORCEPROP 1 LAST PATH I40
J 2
(-7873 5150);
DISPLAY 0.872340 (-7873 5150);
PAINT GREEN (-7873 5150);
DISPLAY INVISIBLE (-7873 5150);
FORCEADD OFFPAGE..1
(-8475 5300);
FORCEPROP 2 LAST $XR0 41 
J 0
(-8726 5300);
DISPLAY 0.638298 (-8726 5300);
PAINT MONO (-8726 5300);
FORCEPROP 2 LAST PATH I41
J 0
(-8725 5350);
DISPLAY 1.021277 (-8725 5350);
DISPLAY INVISIBLE (-8725 5350);
FORCEPROP 1 LAST COMMENT_BODY TRUE
J 0
(-8350 5200);
DISPLAY 0.872340 (-8350 5200);
PAINT GREEN (-8350 5200);
DISPLAY INVISIBLE (-8350 5200);
FORCEPROP 1 LAST OFFPAGE TRUE
J 0
(-8150 5175);
DISPLAY 0.872340 (-8150 5175);
PAINT GREEN (-8150 5175);
DISPLAY INVISIBLE (-8150 5175);
FORCEPROP 2 LAST CDS_LIB mstr_standard
J 0
(-8475 5300);
DISPLAY 0.723404 (-8475 5300);
PAINT MONO (-8475 5300);
DISPLAY INVISIBLE (-8475 5300);
FORCEADD OFFPAGE..1
(-8475 5700);
FORCEPROP 2 LAST $XR0 41 
J 0
(-8726 5700);
DISPLAY 0.638298 (-8726 5700);
PAINT MONO (-8726 5700);
FORCEPROP 2 LAST PATH I42
J 0
(-8725 5750);
DISPLAY 1.021277 (-8725 5750);
DISPLAY INVISIBLE (-8725 5750);
FORCEPROP 1 LAST COMMENT_BODY TRUE
J 0
(-8350 5600);
DISPLAY 0.872340 (-8350 5600);
PAINT GREEN (-8350 5600);
DISPLAY INVISIBLE (-8350 5600);
FORCEPROP 1 LAST OFFPAGE TRUE
J 0
(-8150 5575);
DISPLAY 0.872340 (-8150 5575);
PAINT GREEN (-8150 5575);
DISPLAY INVISIBLE (-8150 5575);
FORCEPROP 2 LAST CDS_LIB mstr_standard
J 0
(-8475 5700);
DISPLAY 0.723404 (-8475 5700);
PAINT MONO (-8475 5700);
DISPLAY INVISIBLE (-8475 5700);
FORCEADD TAP..1
R 2
(-7875 5250);
FORCEPROP 3 LASTPIN (-7825 5250) SIG_NAME M_E_CPU1_SB_CA<6>
J 0
(-7815 5260);
DISPLAY 0.659574 (-7815 5260);
PAINT MONO (-7815 5260);
DISPLAY INVISIBLE (-7815 5260);
FORCEPROP 1 LASTPIN (-7825 5250) BN 6
J 2
(-7813 5258);
DISPLAY 0.489362 (-7813 5258);
PAINT GREEN (-7813 5258);
FORCEPROP 2 LAST CDS_LIB mstr_standard
J 0
(-7875 5250);
DISPLAY 0.723404 (-7875 5250);
PAINT MONO (-7875 5250);
DISPLAY INVISIBLE (-7875 5250);
FORCEPROP 1 LAST BODY_TYPE PLUMBING
J 2
(-7875 5300);
DISPLAY 0.872340 (-7875 5300);
PAINT GREEN (-7875 5300);
DISPLAY INVISIBLE (-7875 5300);
FORCEPROP 1 LAST HDL_TAP TRUE
J 2
(-8200 5125);
DISPLAY 0.872340 (-8200 5125);
DISPLAY INVISIBLE (-8200 5125);
FORCEPROP 1 LAST PATH I43
J 2
(-7873 5250);
DISPLAY 0.872340 (-7873 5250);
PAINT GREEN (-7873 5250);
DISPLAY INVISIBLE (-7873 5250);
FORCEADD TAP..1
R 2
(-7875 5200);
FORCEPROP 3 LASTPIN (-7825 5200) SIG_NAME M_E_CPU1_SB_CA<5>
J 0
(-7815 5210);
DISPLAY 0.659574 (-7815 5210);
PAINT MONO (-7815 5210);
DISPLAY INVISIBLE (-7815 5210);
FORCEPROP 1 LASTPIN (-7825 5200) BN 5
J 2
(-7813 5208);
DISPLAY 0.489362 (-7813 5208);
PAINT GREEN (-7813 5208);
FORCEPROP 2 LAST CDS_LIB mstr_standard
J 0
(-7875 5200);
DISPLAY 0.723404 (-7875 5200);
PAINT MONO (-7875 5200);
DISPLAY INVISIBLE (-7875 5200);
FORCEPROP 1 LAST BODY_TYPE PLUMBING
J 2
(-7875 5250);
DISPLAY 0.872340 (-7875 5250);
PAINT GREEN (-7875 5250);
DISPLAY INVISIBLE (-7875 5250);
FORCEPROP 1 LAST HDL_TAP TRUE
J 2
(-8200 5075);
DISPLAY 0.872340 (-8200 5075);
DISPLAY INVISIBLE (-8200 5075);
FORCEPROP 1 LAST PATH I44
J 2
(-7873 5200);
DISPLAY 0.872340 (-7873 5200);
PAINT GREEN (-7873 5200);
DISPLAY INVISIBLE (-7873 5200);
FORCEADD TAP..1
R 2
(-7875 5350);
FORCEPROP 3 LASTPIN (-7825 5350) SIG_NAME M_E_CPU1_SA_CA<0>
J 0
(-7815 5360);
DISPLAY 0.659574 (-7815 5360);
PAINT MONO (-7815 5360);
DISPLAY INVISIBLE (-7815 5360);
FORCEPROP 1 LASTPIN (-7825 5350) BN 0
J 2
(-7813 5358);
DISPLAY 0.489362 (-7813 5358);
PAINT GREEN (-7813 5358);
FORCEPROP 2 LAST CDS_LIB mstr_standard
J 0
(-7875 5350);
DISPLAY 0.723404 (-7875 5350);
PAINT MONO (-7875 5350);
DISPLAY INVISIBLE (-7875 5350);
FORCEPROP 1 LAST BODY_TYPE PLUMBING
J 2
(-7875 5400);
DISPLAY 0.872340 (-7875 5400);
PAINT GREEN (-7875 5400);
DISPLAY INVISIBLE (-7875 5400);
FORCEPROP 1 LAST HDL_TAP TRUE
J 2
(-8200 5225);
DISPLAY 0.872340 (-8200 5225);
DISPLAY INVISIBLE (-8200 5225);
FORCEPROP 1 LAST PATH I45
J 2
(-7873 5350);
DISPLAY 0.872340 (-7873 5350);
PAINT GREEN (-7873 5350);
DISPLAY INVISIBLE (-7873 5350);
FORCEADD TAP..1
R 2
(-7875 5400);
FORCEPROP 3 LASTPIN (-7825 5400) SIG_NAME M_E_CPU1_SA_CA<1>
J 0
(-7815 5410);
DISPLAY 0.659574 (-7815 5410);
PAINT MONO (-7815 5410);
DISPLAY INVISIBLE (-7815 5410);
FORCEPROP 1 LASTPIN (-7825 5400) BN 1
J 2
(-7813 5408);
DISPLAY 0.489362 (-7813 5408);
PAINT GREEN (-7813 5408);
FORCEPROP 2 LAST CDS_LIB mstr_standard
J 0
(-7875 5400);
DISPLAY 0.723404 (-7875 5400);
PAINT MONO (-7875 5400);
DISPLAY INVISIBLE (-7875 5400);
FORCEPROP 1 LAST BODY_TYPE PLUMBING
J 2
(-7875 5450);
DISPLAY 0.872340 (-7875 5450);
PAINT GREEN (-7875 5450);
DISPLAY INVISIBLE (-7875 5450);
FORCEPROP 1 LAST HDL_TAP TRUE
J 2
(-8200 5275);
DISPLAY 0.872340 (-8200 5275);
DISPLAY INVISIBLE (-8200 5275);
FORCEPROP 1 LAST PATH I46
J 2
(-7873 5400);
DISPLAY 0.872340 (-7873 5400);
PAINT GREEN (-7873 5400);
DISPLAY INVISIBLE (-7873 5400);
FORCEADD TAP..1
R 2
(-7875 5450);
FORCEPROP 3 LASTPIN (-7825 5450) SIG_NAME M_E_CPU1_SA_CA<2>
J 0
(-7815 5460);
DISPLAY 0.659574 (-7815 5460);
PAINT MONO (-7815 5460);
DISPLAY INVISIBLE (-7815 5460);
FORCEPROP 1 LASTPIN (-7825 5450) BN 2
J 2
(-7813 5458);
DISPLAY 0.489362 (-7813 5458);
PAINT GREEN (-7813 5458);
FORCEPROP 2 LAST CDS_LIB mstr_standard
J 0
(-7875 5450);
DISPLAY 0.723404 (-7875 5450);
PAINT MONO (-7875 5450);
DISPLAY INVISIBLE (-7875 5450);
FORCEPROP 1 LAST BODY_TYPE PLUMBING
J 2
(-7875 5500);
DISPLAY 0.872340 (-7875 5500);
PAINT GREEN (-7875 5500);
DISPLAY INVISIBLE (-7875 5500);
FORCEPROP 1 LAST HDL_TAP TRUE
J 2
(-8200 5325);
DISPLAY 0.872340 (-8200 5325);
DISPLAY INVISIBLE (-8200 5325);
FORCEPROP 1 LAST PATH I47
J 2
(-7873 5450);
DISPLAY 0.872340 (-7873 5450);
PAINT GREEN (-7873 5450);
DISPLAY INVISIBLE (-7873 5450);
FORCEADD TAP..1
R 2
(-7875 5500);
FORCEPROP 3 LASTPIN (-7825 5500) SIG_NAME M_E_CPU1_SA_CA<3>
J 0
(-7815 5510);
DISPLAY 0.659574 (-7815 5510);
PAINT MONO (-7815 5510);
DISPLAY INVISIBLE (-7815 5510);
FORCEPROP 1 LASTPIN (-7825 5500) BN 3
J 2
(-7813 5508);
DISPLAY 0.489362 (-7813 5508);
PAINT GREEN (-7813 5508);
FORCEPROP 2 LAST CDS_LIB mstr_standard
J 0
(-7875 5500);
DISPLAY 0.723404 (-7875 5500);
PAINT MONO (-7875 5500);
DISPLAY INVISIBLE (-7875 5500);
FORCEPROP 1 LAST BODY_TYPE PLUMBING
J 2
(-7875 5550);
DISPLAY 0.872340 (-7875 5550);
PAINT GREEN (-7875 5550);
DISPLAY INVISIBLE (-7875 5550);
FORCEPROP 1 LAST HDL_TAP TRUE
J 2
(-8200 5375);
DISPLAY 0.872340 (-8200 5375);
DISPLAY INVISIBLE (-8200 5375);
FORCEPROP 1 LAST PATH I48
J 2
(-7873 5500);
DISPLAY 0.872340 (-7873 5500);
PAINT GREEN (-7873 5500);
DISPLAY INVISIBLE (-7873 5500);
FORCEADD TAP..1
R 2
(-7875 5550);
FORCEPROP 3 LASTPIN (-7825 5550) SIG_NAME M_E_CPU1_SA_CA<4>
J 0
(-7815 5560);
DISPLAY 0.659574 (-7815 5560);
PAINT MONO (-7815 5560);
DISPLAY INVISIBLE (-7815 5560);
FORCEPROP 1 LASTPIN (-7825 5550) BN 4
J 2
(-7813 5558);
DISPLAY 0.489362 (-7813 5558);
PAINT GREEN (-7813 5558);
FORCEPROP 2 LAST CDS_LIB mstr_standard
J 0
(-7875 5550);
DISPLAY 0.723404 (-7875 5550);
PAINT MONO (-7875 5550);
DISPLAY INVISIBLE (-7875 5550);
FORCEPROP 1 LAST BODY_TYPE PLUMBING
J 2
(-7875 5600);
DISPLAY 0.872340 (-7875 5600);
PAINT GREEN (-7875 5600);
DISPLAY INVISIBLE (-7875 5600);
FORCEPROP 1 LAST HDL_TAP TRUE
J 2
(-8200 5425);
DISPLAY 0.872340 (-8200 5425);
DISPLAY INVISIBLE (-8200 5425);
FORCEPROP 1 LAST PATH I49
J 2
(-7873 5550);
DISPLAY 0.872340 (-7873 5550);
PAINT GREEN (-7873 5550);
DISPLAY INVISIBLE (-7873 5550);
FORCEADD TAP..1
R 2
(-7875 5600);
FORCEPROP 3 LASTPIN (-7825 5600) SIG_NAME M_E_CPU1_SA_CA<5>
J 0
(-7815 5610);
DISPLAY 0.659574 (-7815 5610);
PAINT MONO (-7815 5610);
DISPLAY INVISIBLE (-7815 5610);
FORCEPROP 1 LASTPIN (-7825 5600) BN 5
J 2
(-7813 5608);
DISPLAY 0.489362 (-7813 5608);
PAINT GREEN (-7813 5608);
FORCEPROP 2 LAST CDS_LIB mstr_standard
J 0
(-7875 5600);
DISPLAY 0.723404 (-7875 5600);
PAINT MONO (-7875 5600);
DISPLAY INVISIBLE (-7875 5600);
FORCEPROP 1 LAST BODY_TYPE PLUMBING
J 2
(-7875 5650);
DISPLAY 0.872340 (-7875 5650);
PAINT GREEN (-7875 5650);
DISPLAY INVISIBLE (-7875 5650);
FORCEPROP 1 LAST HDL_TAP TRUE
J 2
(-8200 5475);
DISPLAY 0.872340 (-8200 5475);
DISPLAY INVISIBLE (-8200 5475);
FORCEPROP 1 LAST PATH I50
J 2
(-7873 5600);
DISPLAY 0.872340 (-7873 5600);
PAINT GREEN (-7873 5600);
DISPLAY INVISIBLE (-7873 5600);
FORCEADD TAP..1
R 2
(-7875 5650);
FORCEPROP 3 LASTPIN (-7825 5650) SIG_NAME M_E_CPU1_SA_CA<6>
J 0
(-7815 5660);
DISPLAY 0.659574 (-7815 5660);
PAINT MONO (-7815 5660);
DISPLAY INVISIBLE (-7815 5660);
FORCEPROP 1 LASTPIN (-7825 5650) BN 6
J 2
(-7813 5658);
DISPLAY 0.489362 (-7813 5658);
PAINT GREEN (-7813 5658);
FORCEPROP 2 LAST CDS_LIB mstr_standard
J 0
(-7875 5650);
DISPLAY 0.723404 (-7875 5650);
PAINT MONO (-7875 5650);
DISPLAY INVISIBLE (-7875 5650);
FORCEPROP 1 LAST BODY_TYPE PLUMBING
J 2
(-7875 5700);
DISPLAY 0.872340 (-7875 5700);
PAINT GREEN (-7875 5700);
DISPLAY INVISIBLE (-7875 5700);
FORCEPROP 1 LAST HDL_TAP TRUE
J 2
(-8200 5525);
DISPLAY 0.872340 (-8200 5525);
DISPLAY INVISIBLE (-8200 5525);
FORCEPROP 1 LAST PATH I51
J 2
(-7873 5650);
DISPLAY 0.872340 (-7873 5650);
PAINT GREEN (-7873 5650);
DISPLAY INVISIBLE (-7873 5650);
FORCEADD SCONN288_DDR506112002KQ..1
(-7025 3900);
FORCEPROP 1 LAST LOCATION J32
J 0
(-7475 5975);
DISPLAY 0.468085 (-7475 5975);
PAINT SKYBLUE (-7475 5975);
FORCEPROP 0 LAST $SEC 1
J 0
(-7475 6125);
DISPLAY 0.680851 (-7475 6125);
PAINT MONO (-7475 6125);
DISPLAY INVISIBLE (-7475 6125);
FORCEPROP 2 LAST CDS_SEC 1
J 0
(-7475 6125);
DISPLAY 1.021277 (-7475 6125);
DISPLAY INVISIBLE (-7475 6125);
FORCEPROP 0 LASTPIN (-7625 3300) $PN 62
J 2
(-7635 3310);
DISPLAY 0.680851 (-7635 3310);
PAINT MONO (-7635 3310);
FORCEPROP 0 LASTPIN (-7625 5350) $PN 66
J 2
(-7635 5360);
DISPLAY 0.680851 (-7635 5360);
PAINT MONO (-7635 5360);
FORCEPROP 0 LASTPIN (-7625 4950) $PN 76
J 2
(-7635 4960);
DISPLAY 0.680851 (-7635 4960);
PAINT MONO (-7635 4960);
FORCEPROP 0 LASTPIN (-7625 5400) $PN 211
J 2
(-7635 5410);
DISPLAY 0.680851 (-7635 5410);
PAINT MONO (-7635 5410);
FORCEPROP 0 LASTPIN (-7625 5000) $PN 221
J 2
(-7635 5010);
DISPLAY 0.680851 (-7635 5010);
PAINT MONO (-7635 5010);
FORCEPROP 0 LASTPIN (-7625 5450) $PN 68
J 2
(-7635 5460);
DISPLAY 0.680851 (-7635 5460);
PAINT MONO (-7635 5460);
FORCEPROP 0 LASTPIN (-7625 5050) $PN 78
J 2
(-7635 5060);
DISPLAY 0.680851 (-7635 5060);
PAINT MONO (-7635 5060);
FORCEPROP 0 LASTPIN (-7625 5500) $PN 213
J 2
(-7635 5510);
DISPLAY 0.680851 (-7635 5510);
PAINT MONO (-7635 5510);
FORCEPROP 0 LASTPIN (-7625 5100) $PN 223
J 2
(-7635 5110);
DISPLAY 0.680851 (-7635 5110);
PAINT MONO (-7635 5110);
FORCEPROP 0 LASTPIN (-7625 5550) $PN 70
J 2
(-7635 5560);
DISPLAY 0.680851 (-7635 5560);
PAINT MONO (-7635 5560);
FORCEPROP 0 LASTPIN (-7625 5150) $PN 80
J 2
(-7635 5160);
DISPLAY 0.680851 (-7635 5160);
PAINT MONO (-7635 5160);
FORCEPROP 0 LASTPIN (-7625 5600) $PN 215
J 2
(-7635 5610);
DISPLAY 0.680851 (-7635 5610);
PAINT MONO (-7635 5610);
FORCEPROP 0 LASTPIN (-7625 5200) $PN 225
J 2
(-7635 5210);
DISPLAY 0.680851 (-7635 5210);
PAINT MONO (-7635 5210);
FORCEPROP 0 LASTPIN (-7625 5650) $PN 72
J 2
(-7635 5660);
DISPLAY 0.680851 (-7635 5660);
PAINT MONO (-7635 5660);
FORCEPROP 0 LASTPIN (-7625 5250) $PN 82
J 2
(-7635 5260);
DISPLAY 0.680851 (-7635 5260);
PAINT MONO (-7635 5260);
FORCEPROP 0 LASTPIN (-7625 3900) $PN 51
J 2
(-7635 3910);
DISPLAY 0.680851 (-7635 3910);
PAINT MONO (-7635 3910);
FORCEPROP 0 LASTPIN (-7625 3450) $PN 96
J 2
(-7635 3460);
DISPLAY 0.680851 (-7635 3460);
PAINT MONO (-7635 3460);
FORCEPROP 0 LASTPIN (-7625 3950) $PN 53
J 2
(-7635 3960);
DISPLAY 0.680851 (-7635 3960);
PAINT MONO (-7635 3960);
FORCEPROP 0 LASTPIN (-7625 3500) $PN 98
J 2
(-7635 3510);
DISPLAY 0.680851 (-7635 3510);
PAINT MONO (-7635 3510);
FORCEPROP 0 LASTPIN (-7625 4000) $PN 196
J 2
(-7635 4010);
DISPLAY 0.680851 (-7635 4010);
PAINT MONO (-7635 4010);
FORCEPROP 0 LASTPIN (-7625 3550) $PN 241
J 2
(-7635 3560);
DISPLAY 0.680851 (-7635 3560);
PAINT MONO (-7635 3560);
FORCEPROP 0 LASTPIN (-7625 4050) $PN 198
J 2
(-7635 4060);
DISPLAY 0.680851 (-7635 4060);
PAINT MONO (-7635 4060);
FORCEPROP 0 LASTPIN (-7625 3600) $PN 243
J 2
(-7635 3610);
DISPLAY 0.680851 (-7635 3610);
PAINT MONO (-7635 3610);
FORCEPROP 0 LASTPIN (-7625 4100) $PN 58
J 2
(-7635 4110);
DISPLAY 0.680851 (-7635 4110);
PAINT MONO (-7635 4110);
FORCEPROP 0 LASTPIN (-7625 3650) $PN 89
J 2
(-7635 3660);
DISPLAY 0.680851 (-7635 3660);
PAINT MONO (-7635 3660);
FORCEPROP 0 LASTPIN (-7625 4150) $PN 60
J 2
(-7635 4160);
DISPLAY 0.680851 (-7635 4160);
PAINT MONO (-7635 4160);
FORCEPROP 0 LASTPIN (-7625 3700) $PN 91
J 2
(-7635 3710);
DISPLAY 0.680851 (-7635 3710);
PAINT MONO (-7635 3710);
FORCEPROP 0 LASTPIN (-7625 4200) $PN 203
J 2
(-7635 4210);
DISPLAY 0.680851 (-7635 4210);
PAINT MONO (-7635 4210);
FORCEPROP 0 LASTPIN (-7625 3750) $PN 234
J 2
(-7635 3760);
DISPLAY 0.680851 (-7635 3760);
PAINT MONO (-7635 3760);
FORCEPROP 0 LASTPIN (-7625 4250) $PN 205
J 2
(-7635 4260);
DISPLAY 0.680851 (-7635 4260);
PAINT MONO (-7635 4260);
FORCEPROP 0 LASTPIN (-7625 3800) $PN 236
J 2
(-7635 3810);
DISPLAY 0.680851 (-7635 3810);
PAINT MONO (-7635 3810);
FORCEPROP 0 LASTPIN (-7625 4350) $PN 218
J 2
(-7635 4360);
DISPLAY 0.680851 (-7635 4360);
PAINT MONO (-7635 4360);
FORCEPROP 0 LASTPIN (-7625 4400) $PN 217
J 2
(-7635 4410);
DISPLAY 0.680851 (-7635 4410);
PAINT MONO (-7635 4410);
FORCEPROP 0 LASTPIN (-7625 4650) $PN 64
J 2
(-7635 4660);
DISPLAY 0.680851 (-7635 4660);
PAINT MONO (-7635 4660);
FORCEPROP 0 LASTPIN (-7625 4500) $PN 84
J 2
(-7635 4510);
DISPLAY 0.680851 (-7635 4510);
PAINT MONO (-7635 4510);
FORCEPROP 0 LASTPIN (-7625 4700) $PN 209
J 2
(-7635 4710);
DISPLAY 0.680851 (-7635 4710);
PAINT MONO (-7635 4710);
FORCEPROP 0 LASTPIN (-7625 4550) $PN 229
J 2
(-7635 4560);
DISPLAY 0.680851 (-7635 4560);
PAINT MONO (-7635 4560);
FORCEPROP 0 LASTPIN (-6425 4100) $PN 7
J 0
(-6415 4110);
DISPLAY 0.680851 (-6415 4110);
PAINT MONO (-6415 4110);
FORCEPROP 0 LASTPIN (-6425 2450) $PN 100
J 0
(-6415 2460);
DISPLAY 0.680851 (-6415 2460);
PAINT MONO (-6415 2460);
FORCEPROP 0 LASTPIN (-6425 4150) $PN 9
J 0
(-6415 4160);
DISPLAY 0.680851 (-6415 4160);
PAINT MONO (-6415 4160);
FORCEPROP 0 LASTPIN (-6425 2500) $PN 102
J 0
(-6415 2510);
DISPLAY 0.680851 (-6415 2510);
PAINT MONO (-6415 2510);
FORCEPROP 0 LASTPIN (-6425 4200) $PN 152
J 0
(-6415 4210);
DISPLAY 0.680851 (-6415 4210);
PAINT MONO (-6415 4210);
FORCEPROP 0 LASTPIN (-6425 2550) $PN 245
J 0
(-6415 2560);
DISPLAY 0.680851 (-6415 2560);
PAINT MONO (-6415 2560);
FORCEPROP 0 LASTPIN (-6425 4250) $PN 154
J 0
(-6415 4260);
DISPLAY 0.680851 (-6415 4260);
PAINT MONO (-6415 4260);
FORCEPROP 0 LASTPIN (-6425 2600) $PN 247
J 0
(-6415 2610);
DISPLAY 0.680851 (-6415 2610);
PAINT MONO (-6415 2610);
FORCEPROP 0 LASTPIN (-6425 4300) $PN 14
J 0
(-6415 4310);
DISPLAY 0.680851 (-6415 4310);
PAINT MONO (-6415 4310);
FORCEPROP 0 LASTPIN (-6425 2650) $PN 107
J 0
(-6415 2660);
DISPLAY 0.680851 (-6415 2660);
PAINT MONO (-6415 2660);
FORCEPROP 0 LASTPIN (-6425 4350) $PN 16
J 0
(-6415 4360);
DISPLAY 0.680851 (-6415 4360);
PAINT MONO (-6415 4360);
FORCEPROP 0 LASTPIN (-6425 2700) $PN 109
J 0
(-6415 2710);
DISPLAY 0.680851 (-6415 2710);
PAINT MONO (-6415 2710);
FORCEPROP 0 LASTPIN (-6425 4400) $PN 159
J 0
(-6415 4410);
DISPLAY 0.680851 (-6415 4410);
PAINT MONO (-6415 4410);
FORCEPROP 0 LASTPIN (-6425 2750) $PN 252
J 0
(-6415 2760);
DISPLAY 0.680851 (-6415 2760);
PAINT MONO (-6415 2760);
FORCEPROP 0 LASTPIN (-6425 4450) $PN 161
J 0
(-6415 4460);
DISPLAY 0.680851 (-6415 4460);
PAINT MONO (-6415 4460);
FORCEPROP 0 LASTPIN (-6425 2800) $PN 254
J 0
(-6415 2810);
DISPLAY 0.680851 (-6415 2810);
PAINT MONO (-6415 2810);
FORCEPROP 0 LASTPIN (-6425 4500) $PN 18
J 0
(-6415 4510);
DISPLAY 0.680851 (-6415 4510);
PAINT MONO (-6415 4510);
FORCEPROP 0 LASTPIN (-6425 2850) $PN 111
J 0
(-6415 2860);
DISPLAY 0.680851 (-6415 2860);
PAINT MONO (-6415 2860);
FORCEPROP 0 LASTPIN (-6425 4550) $PN 20
J 0
(-6415 4560);
DISPLAY 0.680851 (-6415 4560);
PAINT MONO (-6415 4560);
FORCEPROP 0 LASTPIN (-6425 2900) $PN 113
J 0
(-6415 2910);
DISPLAY 0.680851 (-6415 2910);
PAINT MONO (-6415 2910);
FORCEPROP 0 LASTPIN (-6425 4600) $PN 163
J 0
(-6415 4610);
DISPLAY 0.680851 (-6415 4610);
PAINT MONO (-6415 4610);
FORCEPROP 0 LASTPIN (-6425 2950) $PN 256
J 0
(-6415 2960);
DISPLAY 0.680851 (-6415 2960);
PAINT MONO (-6415 2960);
FORCEPROP 0 LASTPIN (-6425 4650) $PN 165
J 0
(-6415 4660);
DISPLAY 0.680851 (-6415 4660);
PAINT MONO (-6415 4660);
FORCEPROP 0 LASTPIN (-6425 3000) $PN 258
J 0
(-6415 3010);
DISPLAY 0.680851 (-6415 3010);
PAINT MONO (-6415 3010);
FORCEPROP 0 LASTPIN (-6425 4700) $PN 25
J 0
(-6415 4710);
DISPLAY 0.680851 (-6415 4710);
PAINT MONO (-6415 4710);
FORCEPROP 0 LASTPIN (-6425 3050) $PN 118
J 0
(-6415 3060);
DISPLAY 0.680851 (-6415 3060);
PAINT MONO (-6415 3060);
FORCEPROP 0 LASTPIN (-6425 4750) $PN 27
J 0
(-6415 4760);
DISPLAY 0.680851 (-6415 4760);
PAINT MONO (-6415 4760);
FORCEPROP 0 LASTPIN (-6425 3100) $PN 120
J 0
(-6415 3110);
DISPLAY 0.680851 (-6415 3110);
PAINT MONO (-6415 3110);
FORCEPROP 0 LASTPIN (-6425 4800) $PN 170
J 0
(-6415 4810);
DISPLAY 0.680851 (-6415 4810);
PAINT MONO (-6415 4810);
FORCEPROP 0 LASTPIN (-6425 3150) $PN 263
J 0
(-6415 3160);
DISPLAY 0.680851 (-6415 3160);
PAINT MONO (-6415 3160);
FORCEPROP 0 LASTPIN (-6425 4850) $PN 172
J 0
(-6415 4860);
DISPLAY 0.680851 (-6415 4860);
PAINT MONO (-6415 4860);
FORCEPROP 0 LASTPIN (-6425 3200) $PN 265
J 0
(-6415 3210);
DISPLAY 0.680851 (-6415 3210);
PAINT MONO (-6415 3210);
FORCEPROP 0 LASTPIN (-6425 4900) $PN 29
J 0
(-6415 4910);
DISPLAY 0.680851 (-6415 4910);
PAINT MONO (-6415 4910);
FORCEPROP 0 LASTPIN (-6425 3250) $PN 122
J 0
(-6415 3260);
DISPLAY 0.680851 (-6415 3260);
PAINT MONO (-6415 3260);
FORCEPROP 0 LASTPIN (-6425 4950) $PN 31
J 0
(-6415 4960);
DISPLAY 0.680851 (-6415 4960);
PAINT MONO (-6415 4960);
FORCEPROP 0 LASTPIN (-6425 3300) $PN 124
J 0
(-6415 3310);
DISPLAY 0.680851 (-6415 3310);
PAINT MONO (-6415 3310);
FORCEPROP 0 LASTPIN (-6425 5000) $PN 174
J 0
(-6415 5010);
DISPLAY 0.680851 (-6415 5010);
PAINT MONO (-6415 5010);
FORCEPROP 0 LASTPIN (-6425 3350) $PN 267
J 0
(-6415 3360);
DISPLAY 0.680851 (-6415 3360);
PAINT MONO (-6415 3360);
FORCEPROP 0 LASTPIN (-6425 5050) $PN 176
J 0
(-6415 5060);
DISPLAY 0.680851 (-6415 5060);
PAINT MONO (-6415 5060);
FORCEPROP 0 LASTPIN (-6425 3400) $PN 269
J 0
(-6415 3410);
DISPLAY 0.680851 (-6415 3410);
PAINT MONO (-6415 3410);
FORCEPROP 0 LASTPIN (-6425 5100) $PN 36
J 0
(-6415 5110);
DISPLAY 0.680851 (-6415 5110);
PAINT MONO (-6415 5110);
FORCEPROP 0 LASTPIN (-6425 3450) $PN 129
J 0
(-6415 3460);
DISPLAY 0.680851 (-6415 3460);
PAINT MONO (-6415 3460);
FORCEPROP 0 LASTPIN (-6425 5150) $PN 38
J 0
(-6415 5160);
DISPLAY 0.680851 (-6415 5160);
PAINT MONO (-6415 5160);
FORCEPROP 0 LASTPIN (-6425 3500) $PN 131
J 0
(-6415 3510);
DISPLAY 0.680851 (-6415 3510);
PAINT MONO (-6415 3510);
FORCEPROP 0 LASTPIN (-6425 5200) $PN 181
J 0
(-6415 5210);
DISPLAY 0.680851 (-6415 5210);
PAINT MONO (-6415 5210);
FORCEPROP 0 LASTPIN (-6425 3550) $PN 274
J 0
(-6415 3560);
DISPLAY 0.680851 (-6415 3560);
PAINT MONO (-6415 3560);
FORCEPROP 0 LASTPIN (-6425 5250) $PN 183
J 0
(-6415 5260);
DISPLAY 0.680851 (-6415 5260);
PAINT MONO (-6415 5260);
FORCEPROP 0 LASTPIN (-6425 3600) $PN 276
J 0
(-6415 3610);
DISPLAY 0.680851 (-6415 3610);
PAINT MONO (-6415 3610);
FORCEPROP 0 LASTPIN (-6425 5300) $PN 40
J 0
(-6415 5310);
DISPLAY 0.680851 (-6415 5310);
PAINT MONO (-6415 5310);
FORCEPROP 0 LASTPIN (-6425 3650) $PN 133
J 0
(-6415 3660);
DISPLAY 0.680851 (-6415 3660);
PAINT MONO (-6415 3660);
FORCEPROP 0 LASTPIN (-6425 5350) $PN 42
J 0
(-6415 5360);
DISPLAY 0.680851 (-6415 5360);
PAINT MONO (-6415 5360);
FORCEPROP 0 LASTPIN (-6425 3700) $PN 135
J 0
(-6415 3710);
DISPLAY 0.680851 (-6415 3710);
PAINT MONO (-6415 3710);
FORCEPROP 0 LASTPIN (-6425 5400) $PN 185
J 0
(-6415 5410);
DISPLAY 0.680851 (-6415 5410);
PAINT MONO (-6415 5410);
FORCEPROP 0 LASTPIN (-6425 3750) $PN 278
J 0
(-6415 3760);
DISPLAY 0.680851 (-6415 3760);
PAINT MONO (-6415 3760);
FORCEPROP 0 LASTPIN (-6425 5450) $PN 187
J 0
(-6415 5460);
DISPLAY 0.680851 (-6415 5460);
PAINT MONO (-6415 5460);
FORCEPROP 0 LASTPIN (-6425 3800) $PN 280
J 0
(-6415 3810);
DISPLAY 0.680851 (-6415 3810);
PAINT MONO (-6415 3810);
FORCEPROP 0 LASTPIN (-6425 5500) $PN 47
J 0
(-6415 5510);
DISPLAY 0.680851 (-6415 5510);
PAINT MONO (-6415 5510);
FORCEPROP 0 LASTPIN (-6425 3850) $PN 140
J 0
(-6415 3860);
DISPLAY 0.680851 (-6415 3860);
PAINT MONO (-6415 3860);
FORCEPROP 0 LASTPIN (-6425 5550) $PN 49
J 0
(-6415 5560);
DISPLAY 0.680851 (-6415 5560);
PAINT MONO (-6415 5560);
FORCEPROP 0 LASTPIN (-6425 3900) $PN 142
J 0
(-6415 3910);
DISPLAY 0.680851 (-6415 3910);
PAINT MONO (-6415 3910);
FORCEPROP 0 LASTPIN (-6425 5600) $PN 192
J 0
(-6415 5610);
DISPLAY 0.680851 (-6415 5610);
PAINT MONO (-6415 5610);
FORCEPROP 0 LASTPIN (-6425 3950) $PN 285
J 0
(-6415 3960);
DISPLAY 0.680851 (-6415 3960);
PAINT MONO (-6415 3960);
FORCEPROP 0 LASTPIN (-6425 5650) $PN 194
J 0
(-6415 5660);
DISPLAY 0.680851 (-6415 5660);
PAINT MONO (-6415 5660);
FORCEPROP 0 LASTPIN (-6425 4000) $PN 287
J 0
(-6415 4010);
DISPLAY 0.680851 (-6415 4010);
PAINT MONO (-6415 4010);
FORCEPROP 0 LASTPIN (-7625 3150) $PN 148
J 2
(-7635 3160);
DISPLAY 0.680851 (-7635 3160);
PAINT MONO (-7635 3160);
FORCEPROP 0 LASTPIN (-7625 3050) $PN 4
J 2
(-7635 3060);
DISPLAY 0.680851 (-7635 3060);
PAINT MONO (-7635 3060);
FORCEPROP 0 LASTPIN (-7625 3100) $PN 5
J 2
(-7635 3110);
DISPLAY 0.680851 (-7635 3110);
PAINT MONO (-7635 3110);
FORCEPROP 0 LASTPIN (-7625 2250) $PN 86
J 2
(-7635 2260);
DISPLAY 0.680851 (-7635 2260);
PAINT MONO (-7635 2260);
FORCEPROP 0 LASTPIN (-7625 2200) $PN 87
J 2
(-7635 2210);
DISPLAY 0.680851 (-7635 2210);
PAINT MONO (-7635 2210);
FORCEPROP 0 LASTPIN (-7625 4850) $PN 74
J 2
(-7635 4860);
DISPLAY 0.680851 (-7635 4860);
PAINT MONO (-7635 4860);
FORCEPROP 0 LASTPIN (-7625 4800) $PN 227
J 2
(-7635 4810);
DISPLAY 0.680851 (-7635 4810);
PAINT MONO (-7635 4810);
FORCEPROP 0 LASTPIN (-7625 2800) $PN 147
J 2
(-7635 2810);
DISPLAY 0.680851 (-7635 2810);
PAINT MONO (-7635 2810);
FORCEPROP 0 LASTPIN (-7625 3350) $PN 207
J 2
(-7635 3360);
DISPLAY 0.680851 (-7635 3360);
PAINT MONO (-7635 3360);
FORCEPROP 0 LASTPIN (-7625 2400) $PN 2
J 2
(-7635 2410);
DISPLAY 0.680851 (-7635 2410);
PAINT MONO (-7635 2410);
FORCEPROP 0 LASTPIN (-7625 2450) $PN 144
J 2
(-7635 2460);
DISPLAY 0.680851 (-7635 2460);
PAINT MONO (-7635 2460);
FORCEPROP 0 LASTPIN (-7625 2500) $PN 149
J 2
(-7635 2510);
DISPLAY 0.680851 (-7635 2510);
PAINT MONO (-7635 2510);
FORCEPROP 0 LASTPIN (-7625 2550) $PN 150
J 2
(-7635 2560);
DISPLAY 0.680851 (-7635 2560);
PAINT MONO (-7635 2560);
FORCEPROP 0 LASTPIN (-7625 2600) $PN 220
J 2
(-7635 2610);
DISPLAY 0.680851 (-7635 2610);
PAINT MONO (-7635 2610);
FORCEPROP 0 LASTPIN (-7625 2650) $PN 231
J 2
(-7635 2660);
DISPLAY 0.680851 (-7635 2660);
PAINT MONO (-7635 2660);
FORCEPROP 0 LASTPIN (-7625 2700) $PN 232
J 2
(-7635 2710);
DISPLAY 0.680851 (-7635 2710);
PAINT MONO (-7635 2710);
FORCEPROP 0 LASTPIN (-7625 3200) $PN 3
J 2
(-7635 3210);
DISPLAY 0.680851 (-7635 3210);
PAINT MONO (-7635 3210);
FORCEPROP 2 LAST PART_TYPE SMLF
J 0
(-7475 6075);
DISPLAY 1.021277 (-7475 6075);
FORCEPROP 2 LAST VALUE SCONN288_DDR506112002KQ
J 0
(-7475 6025);
DISPLAY 0.489362 (-7475 6025);
PAINT SKYBLUE (-7475 6025);
FORCEPROP 1 LAST PART_NUMBER DFHST8FS479
J 0
(-7475 5900);
DISPLAY 0.468085 (-7475 5900);
PAINT SKYBLUE (-7475 5900);
FORCEPROP 1 LAST MATERIAL IO
J 0
(-7475 5825);
DISPLAY 0.468085 (-7475 5825);
PAINT SKYBLUE (-7475 5825);
FORCEPROP 1 LAST CDS_LMAN_SYM_OUTLINE -450,1900,450,-1850
J 0
(-7025 3900);
DISPLAY 0.468085 (-7025 3900);
PAINT GREEN (-7025 3900);
DISPLAY INVISIBLE (-7025 3900);
FORCEPROP 1 LAST PATH I52
J 0
(-7025 3900);
DISPLAY 0.723404 (-7025 3900);
PAINT GREEN (-7025 3900);
DISPLAY INVISIBLE (-7025 3900);
FORCEPROP 1 LAST NEEDS_NO_SIZE TRUE
J 0
(-7025 3900);
DISPLAY 0.723404 (-7025 3900);
PAINT GREEN (-7025 3900);
DISPLAY INVISIBLE (-7025 3900);
FORCEPROP 2 LAST CDS_LIB pure_quanta
J 0
(-7025 3900);
DISPLAY INVISIBLE (-7025 3900);
FORCEADD TAP..1
(-6175 2550);
FORCEPROP 3 LASTPIN (-6225 2550) SIG_NAME M_E_CPU1_SB_DQ<2>
J 0
(-6215 2560);
DISPLAY 0.659574 (-6215 2560);
PAINT MONO (-6215 2560);
DISPLAY INVISIBLE (-6215 2560);
FORCEPROP 1 LASTPIN (-6225 2550) BN 2
J 0
(-6237 2558);
DISPLAY 0.489362 (-6237 2558);
PAINT GREEN (-6237 2558);
FORCEPROP 2 LAST CDS_LIB mstr_standard
J 0
(-6175 2550);
DISPLAY 0.723404 (-6175 2550);
PAINT MONO (-6175 2550);
DISPLAY INVISIBLE (-6175 2550);
FORCEPROP 1 LAST BODY_TYPE PLUMBING
J 0
(-6175 2600);
DISPLAY 0.872340 (-6175 2600);
PAINT GREEN (-6175 2600);
DISPLAY INVISIBLE (-6175 2600);
FORCEPROP 1 LAST HDL_TAP TRUE
J 0
(-5850 2425);
DISPLAY 0.872340 (-5850 2425);
DISPLAY INVISIBLE (-5850 2425);
FORCEPROP 1 LAST PATH I53
J 0
(-6177 2550);
DISPLAY 0.872340 (-6177 2550);
PAINT GREEN (-6177 2550);
DISPLAY INVISIBLE (-6177 2550);
FORCEADD TAP..1
(-6175 2600);
FORCEPROP 3 LASTPIN (-6225 2600) SIG_NAME M_E_CPU1_SB_DQ<3>
J 0
(-6215 2610);
DISPLAY 0.659574 (-6215 2610);
PAINT MONO (-6215 2610);
DISPLAY INVISIBLE (-6215 2610);
FORCEPROP 1 LASTPIN (-6225 2600) BN 3
J 0
(-6237 2608);
DISPLAY 0.489362 (-6237 2608);
PAINT GREEN (-6237 2608);
FORCEPROP 2 LAST CDS_LIB mstr_standard
J 0
(-6175 2600);
DISPLAY 0.723404 (-6175 2600);
PAINT MONO (-6175 2600);
DISPLAY INVISIBLE (-6175 2600);
FORCEPROP 1 LAST BODY_TYPE PLUMBING
J 0
(-6175 2650);
DISPLAY 0.872340 (-6175 2650);
PAINT GREEN (-6175 2650);
DISPLAY INVISIBLE (-6175 2650);
FORCEPROP 1 LAST HDL_TAP TRUE
J 0
(-5850 2475);
DISPLAY 0.872340 (-5850 2475);
DISPLAY INVISIBLE (-5850 2475);
FORCEPROP 1 LAST PATH I54
J 0
(-6177 2600);
DISPLAY 0.872340 (-6177 2600);
PAINT GREEN (-6177 2600);
DISPLAY INVISIBLE (-6177 2600);
FORCEADD TAP..1
(-6175 2450);
FORCEPROP 3 LASTPIN (-6225 2450) SIG_NAME M_E_CPU1_SB_DQ<0>
J 0
(-6215 2460);
DISPLAY 0.659574 (-6215 2460);
PAINT MONO (-6215 2460);
DISPLAY INVISIBLE (-6215 2460);
FORCEPROP 1 LASTPIN (-6225 2450) BN 0
J 0
(-6237 2458);
DISPLAY 0.489362 (-6237 2458);
PAINT GREEN (-6237 2458);
FORCEPROP 2 LAST CDS_LIB mstr_standard
J 0
(-6175 2450);
DISPLAY 0.723404 (-6175 2450);
PAINT MONO (-6175 2450);
DISPLAY INVISIBLE (-6175 2450);
FORCEPROP 1 LAST BODY_TYPE PLUMBING
J 0
(-6175 2500);
DISPLAY 0.872340 (-6175 2500);
PAINT GREEN (-6175 2500);
DISPLAY INVISIBLE (-6175 2500);
FORCEPROP 1 LAST HDL_TAP TRUE
J 0
(-5850 2325);
DISPLAY 0.872340 (-5850 2325);
DISPLAY INVISIBLE (-5850 2325);
FORCEPROP 1 LAST PATH I55
J 0
(-6177 2450);
DISPLAY 0.872340 (-6177 2450);
PAINT GREEN (-6177 2450);
DISPLAY INVISIBLE (-6177 2450);
FORCEADD TAP..1
(-6175 2500);
FORCEPROP 3 LASTPIN (-6225 2500) SIG_NAME M_E_CPU1_SB_DQ<1>
J 0
(-6215 2510);
DISPLAY 0.659574 (-6215 2510);
PAINT MONO (-6215 2510);
DISPLAY INVISIBLE (-6215 2510);
FORCEPROP 1 LASTPIN (-6225 2500) BN 1
J 0
(-6237 2508);
DISPLAY 0.489362 (-6237 2508);
PAINT GREEN (-6237 2508);
FORCEPROP 2 LAST CDS_LIB mstr_standard
J 0
(-6175 2500);
DISPLAY 0.723404 (-6175 2500);
PAINT MONO (-6175 2500);
DISPLAY INVISIBLE (-6175 2500);
FORCEPROP 1 LAST BODY_TYPE PLUMBING
J 0
(-6175 2550);
DISPLAY 0.872340 (-6175 2550);
PAINT GREEN (-6175 2550);
DISPLAY INVISIBLE (-6175 2550);
FORCEPROP 1 LAST HDL_TAP TRUE
J 0
(-5850 2375);
DISPLAY 0.872340 (-5850 2375);
DISPLAY INVISIBLE (-5850 2375);
FORCEPROP 1 LAST PATH I56
J 0
(-6177 2500);
DISPLAY 0.872340 (-6177 2500);
PAINT GREEN (-6177 2500);
DISPLAY INVISIBLE (-6177 2500);
FORCEADD TAP..1
(-6175 2650);
FORCEPROP 3 LASTPIN (-6225 2650) SIG_NAME M_E_CPU1_SB_DQ<4>
J 0
(-6215 2660);
DISPLAY 0.659574 (-6215 2660);
PAINT MONO (-6215 2660);
DISPLAY INVISIBLE (-6215 2660);
FORCEPROP 1 LASTPIN (-6225 2650) BN 4
J 0
(-6237 2658);
DISPLAY 0.489362 (-6237 2658);
PAINT GREEN (-6237 2658);
FORCEPROP 2 LAST CDS_LIB mstr_standard
J 0
(-6175 2650);
DISPLAY 0.723404 (-6175 2650);
PAINT MONO (-6175 2650);
DISPLAY INVISIBLE (-6175 2650);
FORCEPROP 1 LAST BODY_TYPE PLUMBING
J 0
(-6175 2700);
DISPLAY 0.872340 (-6175 2700);
PAINT GREEN (-6175 2700);
DISPLAY INVISIBLE (-6175 2700);
FORCEPROP 1 LAST HDL_TAP TRUE
J 0
(-5850 2525);
DISPLAY 0.872340 (-5850 2525);
DISPLAY INVISIBLE (-5850 2525);
FORCEPROP 1 LAST PATH I57
J 0
(-6177 2650);
DISPLAY 0.872340 (-6177 2650);
PAINT GREEN (-6177 2650);
DISPLAY INVISIBLE (-6177 2650);
FORCEADD TAP..1
(-6175 2700);
FORCEPROP 3 LASTPIN (-6225 2700) SIG_NAME M_E_CPU1_SB_DQ<5>
J 0
(-6215 2710);
DISPLAY 0.659574 (-6215 2710);
PAINT MONO (-6215 2710);
DISPLAY INVISIBLE (-6215 2710);
FORCEPROP 1 LASTPIN (-6225 2700) BN 5
J 0
(-6237 2708);
DISPLAY 0.489362 (-6237 2708);
PAINT GREEN (-6237 2708);
FORCEPROP 2 LAST CDS_LIB mstr_standard
J 0
(-6175 2700);
DISPLAY 0.723404 (-6175 2700);
PAINT MONO (-6175 2700);
DISPLAY INVISIBLE (-6175 2700);
FORCEPROP 1 LAST BODY_TYPE PLUMBING
J 0
(-6175 2750);
DISPLAY 0.872340 (-6175 2750);
PAINT GREEN (-6175 2750);
DISPLAY INVISIBLE (-6175 2750);
FORCEPROP 1 LAST HDL_TAP TRUE
J 0
(-5850 2575);
DISPLAY 0.872340 (-5850 2575);
DISPLAY INVISIBLE (-5850 2575);
FORCEPROP 1 LAST PATH I58
J 0
(-6177 2700);
DISPLAY 0.872340 (-6177 2700);
PAINT GREEN (-6177 2700);
DISPLAY INVISIBLE (-6177 2700);
FORCEADD TAP..1
(-6175 2750);
FORCEPROP 3 LASTPIN (-6225 2750) SIG_NAME M_E_CPU1_SB_DQ<6>
J 0
(-6215 2760);
DISPLAY 0.659574 (-6215 2760);
PAINT MONO (-6215 2760);
DISPLAY INVISIBLE (-6215 2760);
FORCEPROP 1 LASTPIN (-6225 2750) BN 6
J 0
(-6237 2758);
DISPLAY 0.489362 (-6237 2758);
PAINT GREEN (-6237 2758);
FORCEPROP 2 LAST CDS_LIB mstr_standard
J 0
(-6175 2750);
DISPLAY 0.723404 (-6175 2750);
PAINT MONO (-6175 2750);
DISPLAY INVISIBLE (-6175 2750);
FORCEPROP 1 LAST BODY_TYPE PLUMBING
J 0
(-6175 2800);
DISPLAY 0.872340 (-6175 2800);
PAINT GREEN (-6175 2800);
DISPLAY INVISIBLE (-6175 2800);
FORCEPROP 1 LAST HDL_TAP TRUE
J 0
(-5850 2625);
DISPLAY 0.872340 (-5850 2625);
DISPLAY INVISIBLE (-5850 2625);
FORCEPROP 1 LAST PATH I59
J 0
(-6177 2750);
DISPLAY 0.872340 (-6177 2750);
PAINT GREEN (-6177 2750);
DISPLAY INVISIBLE (-6177 2750);
FORCEADD TAP..1
(-6175 2800);
FORCEPROP 3 LASTPIN (-6225 2800) SIG_NAME M_E_CPU1_SB_DQ<7>
J 0
(-6215 2810);
DISPLAY 0.659574 (-6215 2810);
PAINT MONO (-6215 2810);
DISPLAY INVISIBLE (-6215 2810);
FORCEPROP 1 LASTPIN (-6225 2800) BN 7
J 0
(-6237 2808);
DISPLAY 0.489362 (-6237 2808);
PAINT GREEN (-6237 2808);
FORCEPROP 2 LAST CDS_LIB mstr_standard
J 0
(-6175 2800);
DISPLAY 0.723404 (-6175 2800);
PAINT MONO (-6175 2800);
DISPLAY INVISIBLE (-6175 2800);
FORCEPROP 1 LAST BODY_TYPE PLUMBING
J 0
(-6175 2850);
DISPLAY 0.872340 (-6175 2850);
PAINT GREEN (-6175 2850);
DISPLAY INVISIBLE (-6175 2850);
FORCEPROP 1 LAST HDL_TAP TRUE
J 0
(-5850 2675);
DISPLAY 0.872340 (-5850 2675);
DISPLAY INVISIBLE (-5850 2675);
FORCEPROP 1 LAST PATH I60
J 0
(-6177 2800);
DISPLAY 0.872340 (-6177 2800);
PAINT GREEN (-6177 2800);
DISPLAY INVISIBLE (-6177 2800);
FORCEADD TAP..1
(-6175 2850);
FORCEPROP 3 LASTPIN (-6225 2850) SIG_NAME M_E_CPU1_SB_DQ<8>
J 0
(-6215 2860);
DISPLAY 0.659574 (-6215 2860);
PAINT MONO (-6215 2860);
DISPLAY INVISIBLE (-6215 2860);
FORCEPROP 1 LASTPIN (-6225 2850) BN 8
J 0
(-6237 2858);
DISPLAY 0.489362 (-6237 2858);
PAINT GREEN (-6237 2858);
FORCEPROP 2 LAST CDS_LIB mstr_standard
J 0
(-6175 2850);
DISPLAY 0.723404 (-6175 2850);
PAINT MONO (-6175 2850);
DISPLAY INVISIBLE (-6175 2850);
FORCEPROP 1 LAST BODY_TYPE PLUMBING
J 0
(-6175 2900);
DISPLAY 0.872340 (-6175 2900);
PAINT GREEN (-6175 2900);
DISPLAY INVISIBLE (-6175 2900);
FORCEPROP 1 LAST HDL_TAP TRUE
J 0
(-5850 2725);
DISPLAY 0.872340 (-5850 2725);
DISPLAY INVISIBLE (-5850 2725);
FORCEPROP 1 LAST PATH I61
J 0
(-6177 2850);
DISPLAY 0.872340 (-6177 2850);
PAINT GREEN (-6177 2850);
DISPLAY INVISIBLE (-6177 2850);
FORCEADD TAP..1
(-6175 2900);
FORCEPROP 3 LASTPIN (-6225 2900) SIG_NAME M_E_CPU1_SB_DQ<9>
J 0
(-6215 2910);
DISPLAY 0.659574 (-6215 2910);
PAINT MONO (-6215 2910);
DISPLAY INVISIBLE (-6215 2910);
FORCEPROP 1 LASTPIN (-6225 2900) BN 9
J 0
(-6237 2908);
DISPLAY 0.489362 (-6237 2908);
PAINT GREEN (-6237 2908);
FORCEPROP 2 LAST CDS_LIB mstr_standard
J 0
(-6175 2900);
DISPLAY 0.723404 (-6175 2900);
PAINT MONO (-6175 2900);
DISPLAY INVISIBLE (-6175 2900);
FORCEPROP 1 LAST BODY_TYPE PLUMBING
J 0
(-6175 2950);
DISPLAY 0.872340 (-6175 2950);
PAINT GREEN (-6175 2950);
DISPLAY INVISIBLE (-6175 2950);
FORCEPROP 1 LAST HDL_TAP TRUE
J 0
(-5850 2775);
DISPLAY 0.872340 (-5850 2775);
DISPLAY INVISIBLE (-5850 2775);
FORCEPROP 1 LAST PATH I62
J 0
(-6177 2900);
DISPLAY 0.872340 (-6177 2900);
PAINT GREEN (-6177 2900);
DISPLAY INVISIBLE (-6177 2900);
FORCEADD TAP..1
(-6175 2950);
FORCEPROP 3 LASTPIN (-6225 2950) SIG_NAME M_E_CPU1_SB_DQ<10>
J 0
(-6215 2960);
DISPLAY 0.659574 (-6215 2960);
PAINT MONO (-6215 2960);
DISPLAY INVISIBLE (-6215 2960);
FORCEPROP 1 LASTPIN (-6225 2950) BN 10
J 0
(-6237 2958);
DISPLAY 0.489362 (-6237 2958);
PAINT GREEN (-6237 2958);
FORCEPROP 2 LAST CDS_LIB mstr_standard
J 0
(-6175 2950);
DISPLAY 0.723404 (-6175 2950);
PAINT MONO (-6175 2950);
DISPLAY INVISIBLE (-6175 2950);
FORCEPROP 1 LAST BODY_TYPE PLUMBING
J 0
(-6175 3000);
DISPLAY 0.872340 (-6175 3000);
PAINT GREEN (-6175 3000);
DISPLAY INVISIBLE (-6175 3000);
FORCEPROP 1 LAST HDL_TAP TRUE
J 0
(-5850 2825);
DISPLAY 0.872340 (-5850 2825);
DISPLAY INVISIBLE (-5850 2825);
FORCEPROP 1 LAST PATH I63
J 0
(-6177 2950);
DISPLAY 0.872340 (-6177 2950);
PAINT GREEN (-6177 2950);
DISPLAY INVISIBLE (-6177 2950);
FORCEADD TAP..1
(-6175 3000);
FORCEPROP 3 LASTPIN (-6225 3000) SIG_NAME M_E_CPU1_SB_DQ<11>
J 0
(-6215 3010);
DISPLAY 0.659574 (-6215 3010);
PAINT MONO (-6215 3010);
DISPLAY INVISIBLE (-6215 3010);
FORCEPROP 1 LASTPIN (-6225 3000) BN 11
J 0
(-6237 3008);
DISPLAY 0.489362 (-6237 3008);
PAINT GREEN (-6237 3008);
FORCEPROP 2 LAST CDS_LIB mstr_standard
J 0
(-6175 3000);
DISPLAY 0.723404 (-6175 3000);
PAINT MONO (-6175 3000);
DISPLAY INVISIBLE (-6175 3000);
FORCEPROP 1 LAST BODY_TYPE PLUMBING
J 0
(-6175 3050);
DISPLAY 0.872340 (-6175 3050);
PAINT GREEN (-6175 3050);
DISPLAY INVISIBLE (-6175 3050);
FORCEPROP 1 LAST HDL_TAP TRUE
J 0
(-5850 2875);
DISPLAY 0.872340 (-5850 2875);
DISPLAY INVISIBLE (-5850 2875);
FORCEPROP 1 LAST PATH I64
J 0
(-6177 3000);
DISPLAY 0.872340 (-6177 3000);
PAINT GREEN (-6177 3000);
DISPLAY INVISIBLE (-6177 3000);
FORCEADD TAP..1
(-6175 3100);
FORCEPROP 3 LASTPIN (-6225 3100) SIG_NAME M_E_CPU1_SB_DQ<13>
J 0
(-6215 3110);
DISPLAY 0.659574 (-6215 3110);
PAINT MONO (-6215 3110);
DISPLAY INVISIBLE (-6215 3110);
FORCEPROP 1 LASTPIN (-6225 3100) BN 13
J 0
(-6237 3108);
DISPLAY 0.489362 (-6237 3108);
PAINT GREEN (-6237 3108);
FORCEPROP 2 LAST CDS_LIB mstr_standard
J 0
(-6175 3100);
DISPLAY 0.723404 (-6175 3100);
PAINT MONO (-6175 3100);
DISPLAY INVISIBLE (-6175 3100);
FORCEPROP 1 LAST BODY_TYPE PLUMBING
J 0
(-6175 3150);
DISPLAY 0.872340 (-6175 3150);
PAINT GREEN (-6175 3150);
DISPLAY INVISIBLE (-6175 3150);
FORCEPROP 1 LAST HDL_TAP TRUE
J 0
(-5850 2975);
DISPLAY 0.872340 (-5850 2975);
DISPLAY INVISIBLE (-5850 2975);
FORCEPROP 1 LAST PATH I65
J 0
(-6177 3100);
DISPLAY 0.872340 (-6177 3100);
PAINT GREEN (-6177 3100);
DISPLAY INVISIBLE (-6177 3100);
FORCEADD TAP..1
(-6175 3050);
FORCEPROP 3 LASTPIN (-6225 3050) SIG_NAME M_E_CPU1_SB_DQ<12>
J 0
(-6215 3060);
DISPLAY 0.659574 (-6215 3060);
PAINT MONO (-6215 3060);
DISPLAY INVISIBLE (-6215 3060);
FORCEPROP 1 LASTPIN (-6225 3050) BN 12
J 0
(-6237 3058);
DISPLAY 0.489362 (-6237 3058);
PAINT GREEN (-6237 3058);
FORCEPROP 2 LAST CDS_LIB mstr_standard
J 0
(-6175 3050);
DISPLAY 0.723404 (-6175 3050);
PAINT MONO (-6175 3050);
DISPLAY INVISIBLE (-6175 3050);
FORCEPROP 1 LAST BODY_TYPE PLUMBING
J 0
(-6175 3100);
DISPLAY 0.872340 (-6175 3100);
PAINT GREEN (-6175 3100);
DISPLAY INVISIBLE (-6175 3100);
FORCEPROP 1 LAST HDL_TAP TRUE
J 0
(-5850 2925);
DISPLAY 0.872340 (-5850 2925);
DISPLAY INVISIBLE (-5850 2925);
FORCEPROP 1 LAST PATH I66
J 0
(-6177 3050);
DISPLAY 0.872340 (-6177 3050);
PAINT GREEN (-6177 3050);
DISPLAY INVISIBLE (-6177 3050);
FORCEADD TAP..1
(-6175 3200);
FORCEPROP 3 LASTPIN (-6225 3200) SIG_NAME M_E_CPU1_SB_DQ<15>
J 0
(-6215 3210);
DISPLAY 0.659574 (-6215 3210);
PAINT MONO (-6215 3210);
DISPLAY INVISIBLE (-6215 3210);
FORCEPROP 1 LASTPIN (-6225 3200) BN 15
J 0
(-6237 3208);
DISPLAY 0.489362 (-6237 3208);
PAINT GREEN (-6237 3208);
FORCEPROP 2 LAST CDS_LIB mstr_standard
J 0
(-6175 3200);
DISPLAY 0.723404 (-6175 3200);
PAINT MONO (-6175 3200);
DISPLAY INVISIBLE (-6175 3200);
FORCEPROP 1 LAST BODY_TYPE PLUMBING
J 0
(-6175 3250);
DISPLAY 0.872340 (-6175 3250);
PAINT GREEN (-6175 3250);
DISPLAY INVISIBLE (-6175 3250);
FORCEPROP 1 LAST HDL_TAP TRUE
J 0
(-5850 3075);
DISPLAY 0.872340 (-5850 3075);
DISPLAY INVISIBLE (-5850 3075);
FORCEPROP 1 LAST PATH I67
J 0
(-6177 3200);
DISPLAY 0.872340 (-6177 3200);
PAINT GREEN (-6177 3200);
DISPLAY INVISIBLE (-6177 3200);
FORCEADD TAP..1
(-6175 3150);
FORCEPROP 3 LASTPIN (-6225 3150) SIG_NAME M_E_CPU1_SB_DQ<14>
J 0
(-6215 3160);
DISPLAY 0.659574 (-6215 3160);
PAINT MONO (-6215 3160);
DISPLAY INVISIBLE (-6215 3160);
FORCEPROP 1 LASTPIN (-6225 3150) BN 14
J 0
(-6237 3158);
DISPLAY 0.489362 (-6237 3158);
PAINT GREEN (-6237 3158);
FORCEPROP 2 LAST CDS_LIB mstr_standard
J 0
(-6175 3150);
DISPLAY 0.723404 (-6175 3150);
PAINT MONO (-6175 3150);
DISPLAY INVISIBLE (-6175 3150);
FORCEPROP 1 LAST BODY_TYPE PLUMBING
J 0
(-6175 3200);
DISPLAY 0.872340 (-6175 3200);
PAINT GREEN (-6175 3200);
DISPLAY INVISIBLE (-6175 3200);
FORCEPROP 1 LAST HDL_TAP TRUE
J 0
(-5850 3025);
DISPLAY 0.872340 (-5850 3025);
DISPLAY INVISIBLE (-5850 3025);
FORCEPROP 1 LAST PATH I68
J 0
(-6177 3150);
DISPLAY 0.872340 (-6177 3150);
PAINT GREEN (-6177 3150);
DISPLAY INVISIBLE (-6177 3150);
FORCEADD TAP..1
(-6175 3250);
FORCEPROP 3 LASTPIN (-6225 3250) SIG_NAME M_E_CPU1_SB_DQ<16>
J 0
(-6215 3260);
DISPLAY 0.659574 (-6215 3260);
PAINT MONO (-6215 3260);
DISPLAY INVISIBLE (-6215 3260);
FORCEPROP 1 LASTPIN (-6225 3250) BN 16
J 0
(-6237 3258);
DISPLAY 0.489362 (-6237 3258);
PAINT GREEN (-6237 3258);
FORCEPROP 2 LAST CDS_LIB mstr_standard
J 0
(-6175 3250);
DISPLAY 0.723404 (-6175 3250);
PAINT MONO (-6175 3250);
DISPLAY INVISIBLE (-6175 3250);
FORCEPROP 1 LAST BODY_TYPE PLUMBING
J 0
(-6175 3300);
DISPLAY 0.872340 (-6175 3300);
PAINT GREEN (-6175 3300);
DISPLAY INVISIBLE (-6175 3300);
FORCEPROP 1 LAST HDL_TAP TRUE
J 0
(-5850 3125);
DISPLAY 0.872340 (-5850 3125);
DISPLAY INVISIBLE (-5850 3125);
FORCEPROP 1 LAST PATH I69
J 0
(-6177 3250);
DISPLAY 0.872340 (-6177 3250);
PAINT GREEN (-6177 3250);
DISPLAY INVISIBLE (-6177 3250);
FORCEADD OFFPAGE..1
(-8475 3150);
FORCEPROP 2 LAST $XR0 101 
J 0
(-8757 3150);
DISPLAY 0.638298 (-8757 3150);
PAINT MONO (-8757 3150);
FORCEPROP 2 LAST PATH I7
J 0
(-8750 3200);
DISPLAY 1.021277 (-8750 3200);
DISPLAY INVISIBLE (-8750 3200);
FORCEPROP 1 LAST COMMENT_BODY TRUE
J 0
(-8350 3050);
DISPLAY 0.872340 (-8350 3050);
PAINT GREEN (-8350 3050);
DISPLAY INVISIBLE (-8350 3050);
FORCEPROP 1 LAST OFFPAGE TRUE
J 0
(-8150 3025);
DISPLAY 0.872340 (-8150 3025);
PAINT GREEN (-8150 3025);
DISPLAY INVISIBLE (-8150 3025);
FORCEPROP 2 LAST CDS_LIB mstr_standard
J 0
(-8475 3150);
DISPLAY 0.808511 (-8475 3150);
DISPLAY INVISIBLE (-8475 3150);
FORCEADD TAP..1
(-6175 3350);
FORCEPROP 3 LASTPIN (-6225 3350) SIG_NAME M_E_CPU1_SB_DQ<18>
J 0
(-6215 3360);
DISPLAY 0.659574 (-6215 3360);
PAINT MONO (-6215 3360);
DISPLAY INVISIBLE (-6215 3360);
FORCEPROP 1 LASTPIN (-6225 3350) BN 18
J 0
(-6237 3358);
DISPLAY 0.489362 (-6237 3358);
PAINT GREEN (-6237 3358);
FORCEPROP 2 LAST CDS_LIB mstr_standard
J 0
(-6175 3350);
DISPLAY 0.723404 (-6175 3350);
PAINT MONO (-6175 3350);
DISPLAY INVISIBLE (-6175 3350);
FORCEPROP 1 LAST BODY_TYPE PLUMBING
J 0
(-6175 3400);
DISPLAY 0.872340 (-6175 3400);
PAINT GREEN (-6175 3400);
DISPLAY INVISIBLE (-6175 3400);
FORCEPROP 1 LAST HDL_TAP TRUE
J 0
(-5850 3225);
DISPLAY 0.872340 (-5850 3225);
DISPLAY INVISIBLE (-5850 3225);
FORCEPROP 1 LAST PATH I70
J 0
(-6177 3350);
DISPLAY 0.872340 (-6177 3350);
PAINT GREEN (-6177 3350);
DISPLAY INVISIBLE (-6177 3350);
FORCEADD TAP..1
(-6175 3400);
FORCEPROP 3 LASTPIN (-6225 3400) SIG_NAME M_E_CPU1_SB_DQ<19>
J 0
(-6215 3410);
DISPLAY 0.659574 (-6215 3410);
PAINT MONO (-6215 3410);
DISPLAY INVISIBLE (-6215 3410);
FORCEPROP 1 LASTPIN (-6225 3400) BN 19
J 0
(-6237 3408);
DISPLAY 0.489362 (-6237 3408);
PAINT GREEN (-6237 3408);
FORCEPROP 2 LAST CDS_LIB mstr_standard
J 0
(-6175 3400);
DISPLAY 0.723404 (-6175 3400);
PAINT MONO (-6175 3400);
DISPLAY INVISIBLE (-6175 3400);
FORCEPROP 1 LAST BODY_TYPE PLUMBING
J 0
(-6175 3450);
DISPLAY 0.872340 (-6175 3450);
PAINT GREEN (-6175 3450);
DISPLAY INVISIBLE (-6175 3450);
FORCEPROP 1 LAST HDL_TAP TRUE
J 0
(-5850 3275);
DISPLAY 0.872340 (-5850 3275);
DISPLAY INVISIBLE (-5850 3275);
FORCEPROP 1 LAST PATH I71
J 0
(-6177 3400);
DISPLAY 0.872340 (-6177 3400);
PAINT GREEN (-6177 3400);
DISPLAY INVISIBLE (-6177 3400);
FORCEADD TAP..1
(-6175 3300);
FORCEPROP 3 LASTPIN (-6225 3300) SIG_NAME M_E_CPU1_SB_DQ<17>
J 0
(-6215 3310);
DISPLAY 0.659574 (-6215 3310);
PAINT MONO (-6215 3310);
DISPLAY INVISIBLE (-6215 3310);
FORCEPROP 1 LASTPIN (-6225 3300) BN 17
J 0
(-6237 3308);
DISPLAY 0.489362 (-6237 3308);
PAINT GREEN (-6237 3308);
FORCEPROP 2 LAST CDS_LIB mstr_standard
J 0
(-6175 3300);
DISPLAY 0.723404 (-6175 3300);
PAINT MONO (-6175 3300);
DISPLAY INVISIBLE (-6175 3300);
FORCEPROP 1 LAST BODY_TYPE PLUMBING
J 0
(-6175 3350);
DISPLAY 0.872340 (-6175 3350);
PAINT GREEN (-6175 3350);
DISPLAY INVISIBLE (-6175 3350);
FORCEPROP 1 LAST HDL_TAP TRUE
J 0
(-5850 3175);
DISPLAY 0.872340 (-5850 3175);
DISPLAY INVISIBLE (-5850 3175);
FORCEPROP 1 LAST PATH I72
J 0
(-6177 3300);
DISPLAY 0.872340 (-6177 3300);
PAINT GREEN (-6177 3300);
DISPLAY INVISIBLE (-6177 3300);
FORCEADD TAP..1
(-6175 3500);
FORCEPROP 3 LASTPIN (-6225 3500) SIG_NAME M_E_CPU1_SB_DQ<21>
J 0
(-6215 3510);
DISPLAY 0.659574 (-6215 3510);
PAINT MONO (-6215 3510);
DISPLAY INVISIBLE (-6215 3510);
FORCEPROP 1 LASTPIN (-6225 3500) BN 21
J 0
(-6237 3508);
DISPLAY 0.489362 (-6237 3508);
PAINT GREEN (-6237 3508);
FORCEPROP 2 LAST CDS_LIB mstr_standard
J 0
(-6175 3500);
DISPLAY 0.723404 (-6175 3500);
PAINT MONO (-6175 3500);
DISPLAY INVISIBLE (-6175 3500);
FORCEPROP 1 LAST BODY_TYPE PLUMBING
J 0
(-6175 3550);
DISPLAY 0.872340 (-6175 3550);
PAINT GREEN (-6175 3550);
DISPLAY INVISIBLE (-6175 3550);
FORCEPROP 1 LAST HDL_TAP TRUE
J 0
(-5850 3375);
DISPLAY 0.872340 (-5850 3375);
DISPLAY INVISIBLE (-5850 3375);
FORCEPROP 1 LAST PATH I73
J 0
(-6177 3500);
DISPLAY 0.872340 (-6177 3500);
PAINT GREEN (-6177 3500);
DISPLAY INVISIBLE (-6177 3500);
FORCEADD TAP..1
(-6175 3450);
FORCEPROP 3 LASTPIN (-6225 3450) SIG_NAME M_E_CPU1_SB_DQ<20>
J 0
(-6215 3460);
DISPLAY 0.659574 (-6215 3460);
PAINT MONO (-6215 3460);
DISPLAY INVISIBLE (-6215 3460);
FORCEPROP 1 LASTPIN (-6225 3450) BN 20
J 0
(-6237 3458);
DISPLAY 0.489362 (-6237 3458);
PAINT GREEN (-6237 3458);
FORCEPROP 2 LAST CDS_LIB mstr_standard
J 0
(-6175 3450);
DISPLAY 0.723404 (-6175 3450);
PAINT MONO (-6175 3450);
DISPLAY INVISIBLE (-6175 3450);
FORCEPROP 1 LAST BODY_TYPE PLUMBING
J 0
(-6175 3500);
DISPLAY 0.872340 (-6175 3500);
PAINT GREEN (-6175 3500);
DISPLAY INVISIBLE (-6175 3500);
FORCEPROP 1 LAST HDL_TAP TRUE
J 0
(-5850 3325);
DISPLAY 0.872340 (-5850 3325);
DISPLAY INVISIBLE (-5850 3325);
FORCEPROP 1 LAST PATH I74
J 0
(-6177 3450);
DISPLAY 0.872340 (-6177 3450);
PAINT GREEN (-6177 3450);
DISPLAY INVISIBLE (-6177 3450);
FORCEADD TAP..1
(-6175 3550);
FORCEPROP 3 LASTPIN (-6225 3550) SIG_NAME M_E_CPU1_SB_DQ<22>
J 0
(-6215 3560);
DISPLAY 0.659574 (-6215 3560);
PAINT MONO (-6215 3560);
DISPLAY INVISIBLE (-6215 3560);
FORCEPROP 1 LASTPIN (-6225 3550) BN 22
J 0
(-6237 3558);
DISPLAY 0.489362 (-6237 3558);
PAINT GREEN (-6237 3558);
FORCEPROP 2 LAST CDS_LIB mstr_standard
J 0
(-6175 3550);
DISPLAY 0.723404 (-6175 3550);
PAINT MONO (-6175 3550);
DISPLAY INVISIBLE (-6175 3550);
FORCEPROP 1 LAST BODY_TYPE PLUMBING
J 0
(-6175 3600);
DISPLAY 0.872340 (-6175 3600);
PAINT GREEN (-6175 3600);
DISPLAY INVISIBLE (-6175 3600);
FORCEPROP 1 LAST HDL_TAP TRUE
J 0
(-5850 3425);
DISPLAY 0.872340 (-5850 3425);
DISPLAY INVISIBLE (-5850 3425);
FORCEPROP 1 LAST PATH I75
J 0
(-6177 3550);
DISPLAY 0.872340 (-6177 3550);
PAINT GREEN (-6177 3550);
DISPLAY INVISIBLE (-6177 3550);
FORCEADD TAP..1
(-6175 3650);
FORCEPROP 3 LASTPIN (-6225 3650) SIG_NAME M_E_CPU1_SB_DQ<24>
J 0
(-6215 3660);
DISPLAY 0.659574 (-6215 3660);
PAINT MONO (-6215 3660);
DISPLAY INVISIBLE (-6215 3660);
FORCEPROP 1 LASTPIN (-6225 3650) BN 24
J 0
(-6237 3658);
DISPLAY 0.489362 (-6237 3658);
PAINT GREEN (-6237 3658);
FORCEPROP 2 LAST CDS_LIB mstr_standard
J 0
(-6175 3650);
DISPLAY 0.723404 (-6175 3650);
PAINT MONO (-6175 3650);
DISPLAY INVISIBLE (-6175 3650);
FORCEPROP 1 LAST BODY_TYPE PLUMBING
J 0
(-6175 3700);
DISPLAY 0.872340 (-6175 3700);
PAINT GREEN (-6175 3700);
DISPLAY INVISIBLE (-6175 3700);
FORCEPROP 1 LAST HDL_TAP TRUE
J 0
(-5850 3525);
DISPLAY 0.872340 (-5850 3525);
DISPLAY INVISIBLE (-5850 3525);
FORCEPROP 1 LAST PATH I76
J 0
(-6177 3650);
DISPLAY 0.872340 (-6177 3650);
PAINT GREEN (-6177 3650);
DISPLAY INVISIBLE (-6177 3650);
FORCEADD TAP..1
(-6175 3600);
FORCEPROP 3 LASTPIN (-6225 3600) SIG_NAME M_E_CPU1_SB_DQ<23>
J 0
(-6215 3610);
DISPLAY 0.659574 (-6215 3610);
PAINT MONO (-6215 3610);
DISPLAY INVISIBLE (-6215 3610);
FORCEPROP 1 LASTPIN (-6225 3600) BN 23
J 0
(-6237 3608);
DISPLAY 0.489362 (-6237 3608);
PAINT GREEN (-6237 3608);
FORCEPROP 2 LAST CDS_LIB mstr_standard
J 0
(-6175 3600);
DISPLAY 0.723404 (-6175 3600);
PAINT MONO (-6175 3600);
DISPLAY INVISIBLE (-6175 3600);
FORCEPROP 1 LAST BODY_TYPE PLUMBING
J 0
(-6175 3650);
DISPLAY 0.872340 (-6175 3650);
PAINT GREEN (-6175 3650);
DISPLAY INVISIBLE (-6175 3650);
FORCEPROP 1 LAST HDL_TAP TRUE
J 0
(-5850 3475);
DISPLAY 0.872340 (-5850 3475);
DISPLAY INVISIBLE (-5850 3475);
FORCEPROP 1 LAST PATH I77
J 0
(-6177 3600);
DISPLAY 0.872340 (-6177 3600);
PAINT GREEN (-6177 3600);
DISPLAY INVISIBLE (-6177 3600);
FORCEADD TAP..1
(-6175 3750);
FORCEPROP 3 LASTPIN (-6225 3750) SIG_NAME M_E_CPU1_SB_DQ<26>
J 0
(-6215 3760);
DISPLAY 0.659574 (-6215 3760);
PAINT MONO (-6215 3760);
DISPLAY INVISIBLE (-6215 3760);
FORCEPROP 1 LASTPIN (-6225 3750) BN 26
J 0
(-6237 3758);
DISPLAY 0.489362 (-6237 3758);
PAINT GREEN (-6237 3758);
FORCEPROP 2 LAST CDS_LIB mstr_standard
J 0
(-6175 3750);
DISPLAY 0.723404 (-6175 3750);
PAINT MONO (-6175 3750);
DISPLAY INVISIBLE (-6175 3750);
FORCEPROP 1 LAST BODY_TYPE PLUMBING
J 0
(-6175 3800);
DISPLAY 0.872340 (-6175 3800);
PAINT GREEN (-6175 3800);
DISPLAY INVISIBLE (-6175 3800);
FORCEPROP 1 LAST HDL_TAP TRUE
J 0
(-5850 3625);
DISPLAY 0.872340 (-5850 3625);
DISPLAY INVISIBLE (-5850 3625);
FORCEPROP 1 LAST PATH I78
J 0
(-6177 3750);
DISPLAY 0.872340 (-6177 3750);
PAINT GREEN (-6177 3750);
DISPLAY INVISIBLE (-6177 3750);
FORCEADD TAP..1
(-6175 3700);
FORCEPROP 3 LASTPIN (-6225 3700) SIG_NAME M_E_CPU1_SB_DQ<25>
J 0
(-6215 3710);
DISPLAY 0.659574 (-6215 3710);
PAINT MONO (-6215 3710);
DISPLAY INVISIBLE (-6215 3710);
FORCEPROP 1 LASTPIN (-6225 3700) BN 25
J 0
(-6237 3708);
DISPLAY 0.489362 (-6237 3708);
PAINT GREEN (-6237 3708);
FORCEPROP 2 LAST CDS_LIB mstr_standard
J 0
(-6175 3700);
DISPLAY 0.723404 (-6175 3700);
PAINT MONO (-6175 3700);
DISPLAY INVISIBLE (-6175 3700);
FORCEPROP 1 LAST BODY_TYPE PLUMBING
J 0
(-6175 3750);
DISPLAY 0.872340 (-6175 3750);
PAINT GREEN (-6175 3750);
DISPLAY INVISIBLE (-6175 3750);
FORCEPROP 1 LAST HDL_TAP TRUE
J 0
(-5850 3575);
DISPLAY 0.872340 (-5850 3575);
DISPLAY INVISIBLE (-5850 3575);
FORCEPROP 1 LAST PATH I79
J 0
(-6177 3700);
DISPLAY 0.872340 (-6177 3700);
PAINT GREEN (-6177 3700);
DISPLAY INVISIBLE (-6177 3700);
FORCEADD OFFPAGE..1
(-8350 3350);
FORCEPROP 2 LAST $XR0 41 
J 0
(-8601 3350);
DISPLAY 0.638298 (-8601 3350);
PAINT MONO (-8601 3350);
FORCEPROP 2 LAST PATH I8
J 0
(-8550 3400);
DISPLAY 1.021277 (-8550 3400);
DISPLAY INVISIBLE (-8550 3400);
FORCEPROP 1 LAST COMMENT_BODY TRUE
J 0
(-8225 3250);
DISPLAY 0.872340 (-8225 3250);
PAINT GREEN (-8225 3250);
DISPLAY INVISIBLE (-8225 3250);
FORCEPROP 1 LAST OFFPAGE TRUE
J 0
(-8025 3225);
DISPLAY 0.872340 (-8025 3225);
PAINT GREEN (-8025 3225);
DISPLAY INVISIBLE (-8025 3225);
FORCEPROP 2 LAST CDS_LIB mstr_standard
J 0
(-8350 3350);
DISPLAY 0.808511 (-8350 3350);
DISPLAY INVISIBLE (-8350 3350);
FORCEADD TAP..1
(-6175 3800);
FORCEPROP 3 LASTPIN (-6225 3800) SIG_NAME M_E_CPU1_SB_DQ<27>
J 0
(-6215 3810);
DISPLAY 0.659574 (-6215 3810);
PAINT MONO (-6215 3810);
DISPLAY INVISIBLE (-6215 3810);
FORCEPROP 1 LASTPIN (-6225 3800) BN 27
J 0
(-6237 3808);
DISPLAY 0.489362 (-6237 3808);
PAINT GREEN (-6237 3808);
FORCEPROP 2 LAST CDS_LIB mstr_standard
J 0
(-6175 3800);
DISPLAY 0.723404 (-6175 3800);
PAINT MONO (-6175 3800);
DISPLAY INVISIBLE (-6175 3800);
FORCEPROP 1 LAST BODY_TYPE PLUMBING
J 0
(-6175 3850);
DISPLAY 0.872340 (-6175 3850);
PAINT GREEN (-6175 3850);
DISPLAY INVISIBLE (-6175 3850);
FORCEPROP 1 LAST HDL_TAP TRUE
J 0
(-5850 3675);
DISPLAY 0.872340 (-5850 3675);
DISPLAY INVISIBLE (-5850 3675);
FORCEPROP 1 LAST PATH I80
J 0
(-6177 3800);
DISPLAY 0.872340 (-6177 3800);
PAINT GREEN (-6177 3800);
DISPLAY INVISIBLE (-6177 3800);
FORCEADD TAP..1
(-6175 3900);
FORCEPROP 3 LASTPIN (-6225 3900) SIG_NAME M_E_CPU1_SB_DQ<29>
J 0
(-6215 3910);
DISPLAY 0.659574 (-6215 3910);
PAINT MONO (-6215 3910);
DISPLAY INVISIBLE (-6215 3910);
FORCEPROP 1 LASTPIN (-6225 3900) BN 29
J 0
(-6237 3908);
DISPLAY 0.489362 (-6237 3908);
PAINT GREEN (-6237 3908);
FORCEPROP 2 LAST CDS_LIB mstr_standard
J 0
(-6175 3900);
DISPLAY 0.723404 (-6175 3900);
PAINT MONO (-6175 3900);
DISPLAY INVISIBLE (-6175 3900);
FORCEPROP 1 LAST BODY_TYPE PLUMBING
J 0
(-6175 3950);
DISPLAY 0.872340 (-6175 3950);
PAINT GREEN (-6175 3950);
DISPLAY INVISIBLE (-6175 3950);
FORCEPROP 1 LAST HDL_TAP TRUE
J 0
(-5850 3775);
DISPLAY 0.872340 (-5850 3775);
DISPLAY INVISIBLE (-5850 3775);
FORCEPROP 1 LAST PATH I81
J 0
(-6177 3900);
DISPLAY 0.872340 (-6177 3900);
PAINT GREEN (-6177 3900);
DISPLAY INVISIBLE (-6177 3900);
FORCEADD TAP..1
(-6175 3850);
FORCEPROP 3 LASTPIN (-6225 3850) SIG_NAME M_E_CPU1_SB_DQ<28>
J 0
(-6215 3860);
DISPLAY 0.659574 (-6215 3860);
PAINT MONO (-6215 3860);
DISPLAY INVISIBLE (-6215 3860);
FORCEPROP 1 LASTPIN (-6225 3850) BN 28
J 0
(-6237 3858);
DISPLAY 0.489362 (-6237 3858);
PAINT GREEN (-6237 3858);
FORCEPROP 2 LAST CDS_LIB mstr_standard
J 0
(-6175 3850);
DISPLAY 0.723404 (-6175 3850);
PAINT MONO (-6175 3850);
DISPLAY INVISIBLE (-6175 3850);
FORCEPROP 1 LAST BODY_TYPE PLUMBING
J 0
(-6175 3900);
DISPLAY 0.872340 (-6175 3900);
PAINT GREEN (-6175 3900);
DISPLAY INVISIBLE (-6175 3900);
FORCEPROP 1 LAST HDL_TAP TRUE
J 0
(-5850 3725);
DISPLAY 0.872340 (-5850 3725);
DISPLAY INVISIBLE (-5850 3725);
FORCEPROP 1 LAST PATH I82
J 0
(-6177 3850);
DISPLAY 0.872340 (-6177 3850);
PAINT GREEN (-6177 3850);
DISPLAY INVISIBLE (-6177 3850);
FORCEADD TAP..1
(-6175 3950);
FORCEPROP 3 LASTPIN (-6225 3950) SIG_NAME M_E_CPU1_SB_DQ<30>
J 0
(-6215 3960);
DISPLAY 0.659574 (-6215 3960);
PAINT MONO (-6215 3960);
DISPLAY INVISIBLE (-6215 3960);
FORCEPROP 1 LASTPIN (-6225 3950) BN 30
J 0
(-6237 3958);
DISPLAY 0.489362 (-6237 3958);
PAINT GREEN (-6237 3958);
FORCEPROP 2 LAST CDS_LIB mstr_standard
J 0
(-6175 3950);
DISPLAY 0.723404 (-6175 3950);
PAINT MONO (-6175 3950);
DISPLAY INVISIBLE (-6175 3950);
FORCEPROP 1 LAST BODY_TYPE PLUMBING
J 0
(-6175 4000);
DISPLAY 0.872340 (-6175 4000);
PAINT GREEN (-6175 4000);
DISPLAY INVISIBLE (-6175 4000);
FORCEPROP 1 LAST HDL_TAP TRUE
J 0
(-5850 3825);
DISPLAY 0.872340 (-5850 3825);
DISPLAY INVISIBLE (-5850 3825);
FORCEPROP 1 LAST PATH I83
J 0
(-6177 3950);
DISPLAY 0.872340 (-6177 3950);
PAINT GREEN (-6177 3950);
DISPLAY INVISIBLE (-6177 3950);
FORCEADD TAP..1
(-6175 4000);
FORCEPROP 3 LASTPIN (-6225 4000) SIG_NAME M_E_CPU1_SB_DQ<31>
J 0
(-6215 4010);
DISPLAY 0.659574 (-6215 4010);
PAINT MONO (-6215 4010);
DISPLAY INVISIBLE (-6215 4010);
FORCEPROP 1 LASTPIN (-6225 4000) BN 31
J 0
(-6237 4008);
DISPLAY 0.489362 (-6237 4008);
PAINT GREEN (-6237 4008);
FORCEPROP 2 LAST CDS_LIB mstr_standard
J 0
(-6175 4000);
DISPLAY 0.723404 (-6175 4000);
PAINT MONO (-6175 4000);
DISPLAY INVISIBLE (-6175 4000);
FORCEPROP 1 LAST BODY_TYPE PLUMBING
J 0
(-6175 4050);
DISPLAY 0.872340 (-6175 4050);
PAINT GREEN (-6175 4050);
DISPLAY INVISIBLE (-6175 4050);
FORCEPROP 1 LAST HDL_TAP TRUE
J 0
(-5850 3875);
DISPLAY 0.872340 (-5850 3875);
DISPLAY INVISIBLE (-5850 3875);
FORCEPROP 1 LAST PATH I84
J 0
(-6177 4000);
DISPLAY 0.872340 (-6177 4000);
PAINT GREEN (-6177 4000);
DISPLAY INVISIBLE (-6177 4000);
FORCEADD TAP..1
(-6175 4150);
FORCEPROP 3 LASTPIN (-6225 4150) SIG_NAME M_E_CPU1_SA_DQ<1>
J 0
(-6215 4160);
DISPLAY 0.659574 (-6215 4160);
PAINT MONO (-6215 4160);
DISPLAY INVISIBLE (-6215 4160);
FORCEPROP 1 LASTPIN (-6225 4150) BN 1
J 0
(-6237 4158);
DISPLAY 0.489362 (-6237 4158);
PAINT GREEN (-6237 4158);
FORCEPROP 2 LAST CDS_LIB mstr_standard
J 0
(-6175 4150);
DISPLAY 0.723404 (-6175 4150);
PAINT MONO (-6175 4150);
DISPLAY INVISIBLE (-6175 4150);
FORCEPROP 1 LAST BODY_TYPE PLUMBING
J 0
(-6175 4200);
DISPLAY 0.872340 (-6175 4200);
PAINT GREEN (-6175 4200);
DISPLAY INVISIBLE (-6175 4200);
FORCEPROP 1 LAST HDL_TAP TRUE
J 0
(-5850 4025);
DISPLAY 0.872340 (-5850 4025);
DISPLAY INVISIBLE (-5850 4025);
FORCEPROP 1 LAST PATH I85
J 0
(-6177 4150);
DISPLAY 0.872340 (-6177 4150);
PAINT GREEN (-6177 4150);
DISPLAY INVISIBLE (-6177 4150);
FORCEADD TAP..1
(-6175 4100);
FORCEPROP 3 LASTPIN (-6225 4100) SIG_NAME M_E_CPU1_SA_DQ<0>
J 0
(-6215 4110);
DISPLAY 0.659574 (-6215 4110);
PAINT MONO (-6215 4110);
DISPLAY INVISIBLE (-6215 4110);
FORCEPROP 1 LASTPIN (-6225 4100) BN 0
J 0
(-6237 4108);
DISPLAY 0.489362 (-6237 4108);
PAINT GREEN (-6237 4108);
FORCEPROP 2 LAST CDS_LIB mstr_standard
J 0
(-6175 4100);
DISPLAY 0.723404 (-6175 4100);
PAINT MONO (-6175 4100);
DISPLAY INVISIBLE (-6175 4100);
FORCEPROP 1 LAST BODY_TYPE PLUMBING
J 0
(-6175 4150);
DISPLAY 0.872340 (-6175 4150);
PAINT GREEN (-6175 4150);
DISPLAY INVISIBLE (-6175 4150);
FORCEPROP 1 LAST HDL_TAP TRUE
J 0
(-5850 3975);
DISPLAY 0.872340 (-5850 3975);
DISPLAY INVISIBLE (-5850 3975);
FORCEPROP 1 LAST PATH I86
J 0
(-6177 4100);
DISPLAY 0.872340 (-6177 4100);
PAINT GREEN (-6177 4100);
DISPLAY INVISIBLE (-6177 4100);
FORCEADD OFFPAGE..5
(-8350 3300);
FORCEPROP 2 LAST $XR0 41 
J 0
(-8574 3300);
DISPLAY 0.638298 (-8574 3300);
PAINT MONO (-8574 3300);
FORCEPROP 2 LAST PATH I9
J 0
(-8600 3350);
DISPLAY 1.021277 (-8600 3350);
DISPLAY INVISIBLE (-8600 3350);
FORCEPROP 1 LAST COMMENT_BODY TRUE
J 0
(-8250 3225);
DISPLAY 0.872340 (-8250 3225);
PAINT GREEN (-8250 3225);
DISPLAY INVISIBLE (-8250 3225);
FORCEPROP 1 LAST OFFPAGE TRUE
J 0
(-8025 3175);
DISPLAY 0.872340 (-8025 3175);
PAINT GREEN (-8025 3175);
DISPLAY INVISIBLE (-8025 3175);
FORCEPROP 2 LAST CDS_LIB mstr_standard
J 0
(-8350 3300);
DISPLAY INVISIBLE (-8350 3300);
FORCEADD OFFPAGE..3
(-5500 4050);
FORCEPROP 2 LAST $XR0 41 
J 0
(-5286 4050);
DISPLAY 0.638298 (-5286 4050);
PAINT MONO (-5286 4050);
FORCEPROP 2 LAST PATH I93
J 0
(-5275 4100);
DISPLAY 1.021277 (-5275 4100);
DISPLAY INVISIBLE (-5275 4100);
FORCEPROP 1 LAST COMMENT_BODY TRUE
J 0
(-5550 3950);
DISPLAY 0.872340 (-5550 3950);
PAINT GREEN (-5550 3950);
DISPLAY INVISIBLE (-5550 3950);
FORCEPROP 1 LAST OFFPAGE TRUE
J 0
(-5175 3925);
DISPLAY 0.872340 (-5175 3925);
PAINT GREEN (-5175 3925);
DISPLAY INVISIBLE (-5175 3925);
FORCEPROP 2 LAST CDS_LIB mstr_standard
J 0
(-5500 4050);
DISPLAY 0.723404 (-5500 4050);
PAINT MONO (-5500 4050);
DISPLAY INVISIBLE (-5500 4050);
FORCEADD TAP..1
(-6175 4200);
FORCEPROP 3 LASTPIN (-6225 4200) SIG_NAME M_E_CPU1_SA_DQ<2>
J 0
(-6215 4210);
DISPLAY 0.659574 (-6215 4210);
PAINT MONO (-6215 4210);
DISPLAY INVISIBLE (-6215 4210);
FORCEPROP 1 LASTPIN (-6225 4200) BN 2
J 0
(-6237 4208);
DISPLAY 0.489362 (-6237 4208);
PAINT GREEN (-6237 4208);
FORCEPROP 2 LAST CDS_LIB mstr_standard
J 0
(-6175 4200);
DISPLAY 0.723404 (-6175 4200);
PAINT MONO (-6175 4200);
DISPLAY INVISIBLE (-6175 4200);
FORCEPROP 1 LAST BODY_TYPE PLUMBING
J 0
(-6175 4250);
DISPLAY 0.872340 (-6175 4250);
PAINT GREEN (-6175 4250);
DISPLAY INVISIBLE (-6175 4250);
FORCEPROP 1 LAST HDL_TAP TRUE
J 0
(-5850 4075);
DISPLAY 0.872340 (-5850 4075);
DISPLAY INVISIBLE (-5850 4075);
FORCEPROP 1 LAST PATH I95
J 0
(-6177 4200);
DISPLAY 0.872340 (-6177 4200);
PAINT GREEN (-6177 4200);
DISPLAY INVISIBLE (-6177 4200);
FORCEADD TAP..1
(-6175 4250);
FORCEPROP 3 LASTPIN (-6225 4250) SIG_NAME M_E_CPU1_SA_DQ<3>
J 0
(-6215 4260);
DISPLAY 0.659574 (-6215 4260);
PAINT MONO (-6215 4260);
DISPLAY INVISIBLE (-6215 4260);
FORCEPROP 1 LASTPIN (-6225 4250) BN 3
J 0
(-6237 4258);
DISPLAY 0.489362 (-6237 4258);
PAINT GREEN (-6237 4258);
FORCEPROP 2 LAST CDS_LIB mstr_standard
J 0
(-6175 4250);
DISPLAY 0.723404 (-6175 4250);
PAINT MONO (-6175 4250);
DISPLAY INVISIBLE (-6175 4250);
FORCEPROP 1 LAST BODY_TYPE PLUMBING
J 0
(-6175 4300);
DISPLAY 0.872340 (-6175 4300);
PAINT GREEN (-6175 4300);
DISPLAY INVISIBLE (-6175 4300);
FORCEPROP 1 LAST HDL_TAP TRUE
J 0
(-5850 4125);
DISPLAY 0.872340 (-5850 4125);
DISPLAY INVISIBLE (-5850 4125);
FORCEPROP 1 LAST PATH I96
J 0
(-6177 4250);
DISPLAY 0.872340 (-6177 4250);
PAINT GREEN (-6177 4250);
DISPLAY INVISIBLE (-6177 4250);
FORCEADD TAP..1
(-6175 4300);
FORCEPROP 3 LASTPIN (-6225 4300) SIG_NAME M_E_CPU1_SA_DQ<4>
J 0
(-6215 4310);
DISPLAY 0.659574 (-6215 4310);
PAINT MONO (-6215 4310);
DISPLAY INVISIBLE (-6215 4310);
FORCEPROP 1 LASTPIN (-6225 4300) BN 4
J 0
(-6237 4308);
DISPLAY 0.489362 (-6237 4308);
PAINT GREEN (-6237 4308);
FORCEPROP 2 LAST CDS_LIB mstr_standard
J 0
(-6175 4300);
DISPLAY 0.723404 (-6175 4300);
PAINT MONO (-6175 4300);
DISPLAY INVISIBLE (-6175 4300);
FORCEPROP 1 LAST BODY_TYPE PLUMBING
J 0
(-6175 4350);
DISPLAY 0.872340 (-6175 4350);
PAINT GREEN (-6175 4350);
DISPLAY INVISIBLE (-6175 4350);
FORCEPROP 1 LAST HDL_TAP TRUE
J 0
(-5850 4175);
DISPLAY 0.872340 (-5850 4175);
DISPLAY INVISIBLE (-5850 4175);
FORCEPROP 1 LAST PATH I97
J 0
(-6177 4300);
DISPLAY 0.872340 (-6177 4300);
PAINT GREEN (-6177 4300);
DISPLAY INVISIBLE (-6177 4300);
FORCEADD TAP..1
(-6175 4400);
FORCEPROP 3 LASTPIN (-6225 4400) SIG_NAME M_E_CPU1_SA_DQ<6>
J 0
(-6215 4410);
DISPLAY 0.659574 (-6215 4410);
PAINT MONO (-6215 4410);
DISPLAY INVISIBLE (-6215 4410);
FORCEPROP 1 LASTPIN (-6225 4400) BN 6
J 0
(-6237 4408);
DISPLAY 0.489362 (-6237 4408);
PAINT GREEN (-6237 4408);
FORCEPROP 2 LAST CDS_LIB mstr_standard
J 0
(-6175 4400);
DISPLAY 0.723404 (-6175 4400);
PAINT MONO (-6175 4400);
DISPLAY INVISIBLE (-6175 4400);
FORCEPROP 1 LAST BODY_TYPE PLUMBING
J 0
(-6175 4450);
DISPLAY 0.872340 (-6175 4450);
PAINT GREEN (-6175 4450);
DISPLAY INVISIBLE (-6175 4450);
FORCEPROP 1 LAST HDL_TAP TRUE
J 0
(-5850 4275);
DISPLAY 0.872340 (-5850 4275);
DISPLAY INVISIBLE (-5850 4275);
FORCEPROP 1 LAST PATH I98
J 0
(-6177 4400);
DISPLAY 0.872340 (-6177 4400);
PAINT GREEN (-6177 4400);
DISPLAY INVISIBLE (-6177 4400);
FORCEADD TAP..1
(-6175 4350);
FORCEPROP 3 LASTPIN (-6225 4350) SIG_NAME M_E_CPU1_SA_DQ<5>
J 0
(-6215 4360);
DISPLAY 0.659574 (-6215 4360);
PAINT MONO (-6215 4360);
DISPLAY INVISIBLE (-6215 4360);
FORCEPROP 1 LASTPIN (-6225 4350) BN 5
J 0
(-6237 4358);
DISPLAY 0.489362 (-6237 4358);
PAINT GREEN (-6237 4358);
FORCEPROP 2 LAST CDS_LIB mstr_standard
J 0
(-6175 4350);
DISPLAY 0.723404 (-6175 4350);
PAINT MONO (-6175 4350);
DISPLAY INVISIBLE (-6175 4350);
FORCEPROP 1 LAST BODY_TYPE PLUMBING
J 0
(-6175 4400);
DISPLAY 0.872340 (-6175 4400);
PAINT GREEN (-6175 4400);
DISPLAY INVISIBLE (-6175 4400);
FORCEPROP 1 LAST HDL_TAP TRUE
J 0
(-5850 4225);
DISPLAY 0.872340 (-5850 4225);
DISPLAY INVISIBLE (-5850 4225);
FORCEPROP 1 LAST PATH I99
J 0
(-6177 4350);
DISPLAY 0.872340 (-6177 4350);
PAINT GREEN (-6177 4350);
DISPLAY INVISIBLE (-6177 4350);
FORCEADD QUANTA_TITLE_BLOCK_C..1
(-100 100);
FORCEPROP 0 LAST CDS_CON_LAST_MODIFIED Fri Mar 11 14:53:04 2022
J 0
(-1985 115);
DISPLAY INVISIBLE (-1985 115);
FORCEPROP 1 LAST CUSTOM_TXT_CDS <CON_LAST_MODIFIED>
J 0
(-1985 115);
DISPLAY 0.978723 (-1985 115);
FORCEPROP 2 LAST CUSTOM_TXT_CDS <XR_PAGE_TITLE>
J 0
(-7990 5350);
DISPLAY 0.638298 (-7990 5350);
PAINT PINK (-7990 5350);
DISPLAY INVISIBLE (-7990 5350);
FORCEPROP 1 LAST CUSTOM_TXT_CDS <NAME_2>
J 0
(-3275 150);
FORCEPROP 1 LAST CUSTOM_TXT_CDS <NAME_1>
J 0
(-3275 275);
FORCEPROP 1 LAST CUSTOM_TXT_CDS <Q_NUMBER>
J 0
(-1503 203);
DISPLAY 1.212766 (-1503 203);
FORCEPROP 1 LAST CUSTOM_TXT_CDS <Q_PROJ>
J 0
(-2482 202);
DISPLAY 1.212766 (-2482 202);
FORCEPROP 1 LAST CUSTOM_TXT_CDS <Q_REV>
J 0
(-284 203);
DISPLAY 1.212766 (-284 203);
FORCEPROP 1 LAST CUSTOM_TXT_CDS <CON_PAGE_NUM> OF <CON_TOTAL_PAGES>
J 0
(-546 118);
DISPLAY 0.978723 (-546 118);
FORCEPROP 1 LAST Q_TITLE DDR5 - CPU1 CHE
J 0
(-9425 150);
DISPLAY 2.446809 (-9425 150);
PAINT GREEN (-9425 150);
FORCEPROP 1 LAST Q_DEPT BU9
J 1
(-3863 149);
DISPLAY 1.957447 (-3863 149);
PAINT GREEN (-3863 149);
FORCEPROP 2 LAST PAGE_BORDER TRUE
J 0
(-7990 5350);
DISPLAY 0.638298 (-7990 5350);
PAINT PINK (-7990 5350);
DISPLAY INVISIBLE (-7990 5350);
FORCEPROP 2 LAST CDS_LIB pure_quanta
J 0
(-100 100);
DISPLAY INVISIBLE (-100 100);
FORCEPROP 1 LAST CDS_LMAN_SYM_OUTLINE -9475,6775,100,-125
J 0
(-100 100);
DISPLAY 0.468085 (-100 100);
PAINT GREEN (-100 100);
DISPLAY INVISIBLE (-100 100);
FORCEPROP 1 LAST COMMENT_BODY TRUE
J 0
(-88 87);
DISPLAY 0.978723 (-88 87);
PAINT GREEN (-88 87);
DISPLAY INVISIBLE (-88 87);
FORCEPROP 2 LAST CDS_XR_PAGE_TITLE CR-101 : @T6G_MB_LIB.T6G(SCH_1):PAGE101
J 0
(-7990 5350);
DISPLAY 0.638298 (-7990 5350);
PAINT PINK (-7990 5350);
DISPLAY INVISIBLE (-7990 5350);
FORCEADD DNS..2
(-8475 2550);
PAINT RED (-8475 2550);
FORCEPROP 2 LAST CDS_LIB mstr_misc
J 0
(-8475 2550);
DISPLAY INVISIBLE (-8475 2550);
FORCEPROP 1 LAST COMMENT_BODY TRUE
R 1
J 0
(-8400 2325);
DISPLAY 0.872340 (-8400 2325);
PAINT PEACH (-8400 2325);
DISPLAY INVISIBLE (-8400 2325);
WIRE 17 -1 (-6125 5675)(-6125 5625);
WIRE 17 -1 (-6125 5700)(-6125 5675);
WIRE 17 -1 (-6125 5625)(-6125 5575);
WIRE 17 -1 (-6125 5575)(-6125 5525);
WIRE 17 -1 (-6125 5700)(-5550 5700);
FORCEPROP 2 LAST SIG_NAME M_E_CPU1_SA_DQ<31:0>
J 0
(-6060 5710);
DISPLAY 0.489362 (-6060 5710);
WIRE 17 -1 (-7925 4275)(-7925 4300);
WIRE 17 -1 (-7925 4275)(-7925 4225);
WIRE 17 -1 (-7925 4300)(-8425 4300);
FORCEPROP 2 LAST SIG_NAME M_E_CPU1_SA_CB<7:0>
J 0
(-8375 4310);
DISPLAY 0.489362 (-8375 4310);
WIRE 17 -1 (-7925 4075)(-7925 4125);
WIRE 17 -1 (-7925 4025)(-7925 4075);
WIRE 17 -1 (-7925 4175)(-7925 4125);
WIRE 17 -1 (-7925 4175)(-7925 4225);
WIRE 17 -1 (-7925 3975)(-7925 4025);
WIRE 17 -1 (-7925 3925)(-7925 3975);
WIRE 17 -1 (-7925 3825)(-7925 3775);
WIRE 17 -1 (-7925 3825)(-7925 3850);
WIRE 17 -1 (-7925 3725)(-7925 3775);
WIRE 17 -1 (-7925 3725)(-7925 3675);
WIRE 17 -1 (-7925 3850)(-8425 3850);
FORCEPROP 2 LAST SIG_NAME M_E_CPU1_SB_CB<7:0>
J 0
(-8375 3860);
DISPLAY 0.489362 (-8375 3860);
WIRE 17 -1 (-7925 5375)(-7925 5425);
WIRE 17 -1 (-7925 5425)(-7925 5475);
WIRE 17 -1 (-7925 5475)(-7925 5525);
WIRE 17 -1 (-7925 5525)(-7925 5575);
WIRE 17 -1 (-7925 5575)(-7925 5625);
WIRE 17 -1 (-7925 5625)(-7925 5675);
WIRE 17 -1 (-7925 5675)(-7925 5700);
WIRE 17 -1 (-7925 5700)(-8425 5700);
FORCEPROP 2 LAST SIG_NAME M_E_CPU1_SA_CA<6:0>
J 0
(-8410 5710);
DISPLAY 0.489362 (-8410 5710);
WIRE 17 -1 (-7925 4975)(-7925 5025);
WIRE 17 -1 (-7925 5025)(-7925 5075);
WIRE 17 -1 (-7925 5075)(-7925 5125);
WIRE 17 -1 (-7925 5125)(-7925 5175);
WIRE 17 -1 (-7925 5175)(-7925 5225);
WIRE 17 -1 (-7925 5225)(-7925 5275);
WIRE 17 -1 (-7925 5275)(-7925 5300);
WIRE 17 -1 (-7925 5300)(-8425 5300);
FORCEPROP 2 LAST SIG_NAME M_E_CPU1_SB_CA<6:0>
J 0
(-8410 5310);
DISPLAY 0.489362 (-8410 5310);
WIRE 17 -1 (-7925 3625)(-7925 3675);
WIRE 17 -1 (-7925 3575)(-7925 3625);
WIRE 17 -1 (-7925 3525)(-7925 3575);
WIRE 17 -1 (-7925 3475)(-7925 3525);
WIRE 17 -1 (-6125 5525)(-6125 5475);
WIRE 17 -1 (-6125 5475)(-6125 5425);
WIRE 17 -1 (-6125 5425)(-6125 5375);
WIRE 17 -1 (-6125 5375)(-6125 5325);
WIRE 17 -1 (-6125 5325)(-6125 5275);
WIRE 17 -1 (-6125 5275)(-6125 5225);
WIRE 17 -1 (-6125 5225)(-6125 5175);
WIRE 17 -1 (-6125 5175)(-6125 5125);
WIRE 17 -1 (-6125 5125)(-6125 5075);
WIRE 17 -1 (-6125 5075)(-6125 5025);
WIRE 17 -1 (-6125 5025)(-6125 4975);
WIRE 17 -1 (-6125 4975)(-6125 4925);
WIRE 17 -1 (-6125 4875)(-6125 4925);
WIRE 17 -1 (-6125 4825)(-6125 4875);
WIRE 17 -1 (-6125 4775)(-6125 4825);
WIRE 17 -1 (-6125 4725)(-6125 4775);
WIRE 17 -1 (-6125 4725)(-6125 4675);
WIRE 17 -1 (-6125 4675)(-6125 4625);
WIRE 17 -1 (-6125 4625)(-6125 4575);
WIRE 17 -1 (-6125 4575)(-6125 4525);
WIRE 17 -1 (-6125 4525)(-6125 4475);
WIRE 17 -1 (-6125 4475)(-6125 4425);
WIRE 17 -1 (-6125 4425)(-6125 4375);
WIRE 17 -1 (-6125 4375)(-6125 4325);
WIRE 17 -1 (-6125 4275)(-6125 4325);
WIRE 17 -1 (-6125 4225)(-6125 4275);
WIRE 17 -1 (-6125 4175)(-6125 4225);
WIRE 17 -1 (-6125 4125)(-6125 4175);
WIRE 17 -1 (-6125 4050)(-6125 4025);
WIRE 17 -1 (-6125 4050)(-5550 4050);
FORCEPROP 2 LAST SIG_NAME M_E_CPU1_SB_DQ<31:0>
J 0
(-6060 4060);
DISPLAY 0.489362 (-6060 4060);
WIRE 17 -1 (-6125 3975)(-6125 3925);
WIRE 17 -1 (-6125 4025)(-6125 3975);
WIRE 17 -1 (-6125 3925)(-6125 3875);
WIRE 17 -1 (-6125 3875)(-6125 3825);
WIRE 17 -1 (-6125 3825)(-6125 3775);
WIRE 17 -1 (-6125 3775)(-6125 3725);
WIRE 17 -1 (-6125 3725)(-6125 3675);
WIRE 17 -1 (-6125 3675)(-6125 3625);
WIRE 17 -1 (-6125 3625)(-6125 3575);
WIRE 17 -1 (-6125 3575)(-6125 3525);
WIRE 17 -1 (-6125 3525)(-6125 3475);
WIRE 17 -1 (-6125 3475)(-6125 3425);
WIRE 17 -1 (-6125 3425)(-6125 3375);
WIRE 17 -1 (-6125 3375)(-6125 3325);
WIRE 17 -1 (-6125 3325)(-6125 3275);
WIRE 17 -1 (-6125 3225)(-6125 3275);
WIRE 17 -1 (-6125 3175)(-6125 3225);
WIRE 17 -1 (-6125 3125)(-6125 3175);
WIRE 17 -1 (-6125 3075)(-6125 3125);
WIRE 17 -1 (-6125 3075)(-6125 3025);
WIRE 17 -1 (-6125 3025)(-6125 2975);
WIRE 17 -1 (-6125 2975)(-6125 2925);
WIRE 17 -1 (-6125 2925)(-6125 2875);
WIRE 17 -1 (-6125 2875)(-6125 2825);
WIRE 17 -1 (-6125 2825)(-6125 2775);
WIRE 17 -1 (-6125 2775)(-6125 2725);
WIRE 17 -1 (-6125 2725)(-6125 2675);
WIRE 17 -1 (-6125 2625)(-6125 2675);
WIRE 17 -1 (-6125 2575)(-6125 2625);
WIRE 17 -1 (-6125 2525)(-6125 2575);
WIRE 17 -1 (-6125 2475)(-6125 2525);
WIRE 17 -1 (-3225 4550)(-3225 4450);
WIRE 17 -1 (-3225 4650)(-3225 4550);
WIRE 17 -1 (-3225 4450)(-3225 4350);
WIRE 17 -1 (-3225 4250)(-3225 4350);
WIRE 17 -1 (-3225 4750)(-3225 4650);
WIRE 17 -1 (-3225 4775)(-3225 4750);
WIRE 17 -1 (-3225 4150)(-3225 4250);
WIRE 17 -1 (-3225 4050)(-3225 4150);
WIRE 17 -1 (-3225 4775)(-2525 4775);
FORCEPROP 2 LAST SIG_NAME M_E_CPU1_SA_DQS_DN<9:0>
J 0
(-3160 4785);
DISPLAY 0.489362 (-3160 4785);
WIRE 17 -1 (-3425 4500)(-3425 4400);
WIRE 17 -1 (-3425 4600)(-3425 4500);
WIRE 17 -1 (-3425 4300)(-3425 4400);
WIRE 17 -1 (-3425 4200)(-3425 4300);
WIRE 17 -1 (-3425 4700)(-3425 4600);
WIRE 17 -1 (-3425 4800)(-3425 4700);
WIRE 17 -1 (-3425 4100)(-3425 4200);
WIRE 17 -1 (-3425 4100)(-3425 4000);
WIRE 17 -1 (-3425 4825)(-3425 4800);
WIRE 17 -1 (-3425 4825)(-2525 4825);
FORCEPROP 2 LAST SIG_NAME M_E_CPU1_SA_DQS_DP<9:0>
J 0
(-3160 4835);
DISPLAY 0.489362 (-3160 4835);
WIRE 17 -1 (-3425 3650)(-3425 3550);
WIRE 17 -1 (-3425 3750)(-3425 3650);
WIRE 17 -1 (-3425 3550)(-3425 3450);
WIRE 17 -1 (-3425 3450)(-3425 3350);
WIRE 17 -1 (-3425 3775)(-3425 3750);
WIRE 17 -1 (-3425 3775)(-2525 3775);
FORCEPROP 2 LAST SIG_NAME M_E_CPU1_SB_DQS_DP<9:0>
J 0
(-3160 3785);
DISPLAY 0.489362 (-3160 3785);
WIRE 17 -1 (-3225 3600)(-3225 3500);
WIRE 17 -1 (-3225 3700)(-3225 3600);
WIRE 17 -1 (-3225 3500)(-3225 3400);
WIRE 17 -1 (-3225 3400)(-3225 3300);
WIRE 17 -1 (-3225 3725)(-3225 3700);
WIRE 17 -1 (-3225 3725)(-2525 3725);
FORCEPROP 2 LAST SIG_NAME M_E_CPU1_SB_DQS_DN<9:0>
J 0
(-3160 3735);
DISPLAY 0.489362 (-3160 3735);
WIRE 17 -1 (-3425 3250)(-3425 3350);
WIRE 17 -1 (-3425 3150)(-3425 3250);
WIRE 17 -1 (-3425 3050)(-3425 3150);
WIRE 17 -1 (-3225 3950)(-3225 3850);
WIRE 17 -1 (-3225 4050)(-3225 3950);
WIRE 17 -1 (-3425 4000)(-3425 3900);
WIRE 17 -1 (-3225 2900)(-3225 2800);
WIRE 17 -1 (-3225 3000)(-3225 2900);
WIRE 17 -1 (-3225 3000)(-3225 3100);
WIRE 17 -1 (-3225 3100)(-3225 3200);
WIRE 17 -1 (-3225 3200)(-3225 3300);
WIRE 17 -1 (-3425 2950)(-3425 2850);
WIRE 17 -1 (-3425 3050)(-3425 2950);
WIRE 16 -1 (-6575 1300)(-6575 1375);
WIRE 16 -1 (-8800 3300)(-8800 3375);
WIRE 16 -1 (-8500 2650)(-8500 2675);
WIRE 16 -1 (-8800 3575)(-8800 3600);
WIRE 16 -1 (-8800 3600)(-8700 3600);
WIRE 16 -1 (-8700 3625)(-8700 3600);
WIRE 16 -1 (-8700 3600)(-8700 3200);
WIRE 16 -1 (-8700 3200)(-7625 3200);
WIRE 16 -1 (-7625 3100)(-8425 3100);
FORCEPROP 2 LAST SIG_NAME I3C_SPD_DDRAF_CPU1_SDA
J 0
(-8435 3110);
DISPLAY 0.489362 (-8435 3110);
WIRE 16 -1 (-7725 3050)(-7725 2925);
WIRE 16 -1 (-7625 3050)(-7725 3050);
FORCEPROP 2 LAST SIG_NAME I3C_SPD_DDRE_CPU1_SCL
J 0
(-8110 3060);
DISPLAY 0.446809 (-8110 3060);
FORCEPROP 2 LASTPROP $XRERR UNIQUE?
J 0
(-8350 3060);
DISPLAY 0.638298 (-8350 3060);
PAINT MONO (-8350 3060);
DISPLAY INVISIBLE (-8350 3060);
WIRE 16 -1 (-7725 2925)(-7825 2925);
WIRE 16 -1 (-8025 2925)(-8425 2925);
FORCEPROP 2 LAST SIG_NAME I3C_SPD_DDRAF_CPU1_SCL
J 0
(-8485 2935);
DISPLAY 0.489362 (-8485 2935);
WIRE 16 -1 (-8300 2400)(-8500 2400);
WIRE 16 -1 (-8300 2400)(-8300 2800);
WIRE 16 -1 (-8500 2450)(-8500 2400);
WIRE 16 -1 (-8500 2400)(-8525 2400);
WIRE 16 -1 (-7625 2800)(-8300 2800);
FORCEPROP 2 LAST SIG_NAME PWRGD_CHE_CPU1_DIMM
J 0
(-8185 2810);
DISPLAY 0.489362 (-8185 2810);
FORCEPROP 2 LASTPROP $XRERR UNIQUE?
J 0
(-8425 2810);
DISPLAY 0.638298 (-8425 2810);
PAINT MONO (-8425 2810);
DISPLAY INVISIBLE (-8425 2810);
WIRE 16 -1 (-7625 2700)(-8200 2700);
FORCEPROP 2 LAST SIG_NAME TP_CHE_CPU1_DIMM_RFU_6
J 0
(-8210 2710);
DISPLAY 0.489362 (-8210 2710);
FORCEPROP 2 LASTPROP $XRERR UNIQUE?
J 0
(-8440 2700);
DISPLAY 0.638298 (-8440 2700);
PAINT MONO (-8440 2700);
DISPLAY INVISIBLE (-8440 2700);
WIRE 16 -1 (-7625 3150)(-8425 3150);
FORCEPROP 2 LAST SIG_NAME PD_CHE_CPU1_DIMM_SAA
J 0
(-8400 3160);
DISPLAY 0.489362 (-8400 3160);
WIRE 16 -1 (-7625 3300)(-8300 3300);
FORCEPROP 2 LAST SIG_NAME M_E_CPU1_ALERT_N
J 0
(-8285 3310);
DISPLAY 0.489362 (-8285 3310);
WIRE 16 -1 (-7625 3350)(-8300 3350);
FORCEPROP 2 LAST SIG_NAME M_E_CPU1_RESET_N
J 0
(-8285 3360);
DISPLAY 0.489362 (-8285 3360);
WIRE 16 -1 (-7625 2250)(-8425 2250);
FORCEPROP 2 LAST SIG_NAME M_E_CPU1_SA_RSP<0>
J 0
(-8375 2260);
DISPLAY 0.489362 (-8375 2260);
WIRE 16 -1 (-9075 2400)(-8725 2400);
FORCEPROP 2 LAST SIG_NAME PWRGD_CHAF_CPU1
J 0
(-9085 2410);
DISPLAY 0.489362 (-9085 2410);
WIRE 16 -1 (-2175 5550)(-1875 5550);
WIRE 16 -1 (-2175 5600)(-2175 5550);
WIRE 16 -1 (-1875 5600)(-2175 5600);
WIRE 16 -1 (-2175 5600)(-2175 5650);
WIRE 16 -1 (-1875 5650)(-2175 5650);
WIRE 16 -1 (-2175 5650)(-2175 6375);
WIRE 16 -1 (-2300 6375)(-2175 6375);
WIRE 16 -1 (-2300 6375)(-2875 6375);
WIRE 16 -1 (-2300 6375)(-2300 6275);
WIRE 16 -1 (-2875 6375)(-2875 6450);
WIRE 16 -1 (-2875 6275)(-2875 6375);
WIRE 16 -1 (-2300 5950)(-2875 5950);
WIRE 16 -1 (-2300 5950)(-2300 6075);
WIRE 16 -1 (-2875 5950)(-2875 6075);
WIRE 16 -1 (-2875 5950)(-2875 5875);
WIRE 16 -1 (-375 2350)(-375 2300);
WIRE 16 -1 (-375 2400)(-375 2350);
WIRE 16 -1 (-375 2350)(-675 2350);
WIRE 16 -1 (-375 2300)(-375 2125);
WIRE 16 -1 (-375 2300)(-675 2300);
WIRE 16 -1 (-375 2500)(-375 2400);
WIRE 16 -1 (-375 2400)(-675 2400);
WIRE 16 -1 (-375 2550)(-375 2500);
WIRE 16 -1 (-375 2500)(-675 2500);
WIRE 16 -1 (-375 2600)(-375 2550);
WIRE 16 -1 (-375 2550)(-675 2550);
WIRE 16 -1 (-375 2650)(-375 2600);
WIRE 16 -1 (-375 2600)(-675 2600);
WIRE 16 -1 (-375 2700)(-375 2650);
WIRE 16 -1 (-375 2650)(-675 2650);
WIRE 16 -1 (-375 2750)(-375 2700);
WIRE 16 -1 (-375 2700)(-675 2700);
WIRE 16 -1 (-375 2800)(-375 2750);
WIRE 16 -1 (-375 2750)(-675 2750);
WIRE 16 -1 (-375 2850)(-375 2800);
WIRE 16 -1 (-375 2800)(-675 2800);
WIRE 16 -1 (-375 2900)(-375 2850);
WIRE 16 -1 (-375 2850)(-675 2850);
WIRE 16 -1 (-375 2950)(-375 2900);
WIRE 16 -1 (-375 2900)(-675 2900);
WIRE 16 -1 (-375 3000)(-375 2950);
WIRE 16 -1 (-375 2950)(-675 2950);
WIRE 16 -1 (-375 3050)(-375 3000);
WIRE 16 -1 (-375 3000)(-675 3000);
WIRE 16 -1 (-375 3100)(-375 3050);
WIRE 16 -1 (-375 3050)(-675 3050);
WIRE 16 -1 (-375 3150)(-375 3100);
WIRE 16 -1 (-375 3100)(-675 3100);
WIRE 16 -1 (-375 3200)(-375 3150);
WIRE 16 -1 (-375 3150)(-675 3150);
WIRE 16 -1 (-375 3250)(-375 3200);
WIRE 16 -1 (-375 3200)(-675 3200);
WIRE 16 -1 (-375 3300)(-375 3250);
WIRE 16 -1 (-375 3250)(-675 3250);
WIRE 16 -1 (-375 3350)(-375 3300);
WIRE 16 -1 (-375 3300)(-675 3300);
WIRE 16 -1 (-375 3400)(-375 3350);
WIRE 16 -1 (-375 3350)(-675 3350);
WIRE 16 -1 (-375 3450)(-375 3400);
WIRE 16 -1 (-375 3400)(-675 3400);
WIRE 16 -1 (-375 3500)(-375 3450);
WIRE 16 -1 (-375 3450)(-675 3450);
WIRE 16 -1 (-375 3550)(-375 3500);
WIRE 16 -1 (-375 3500)(-675 3500);
WIRE 16 -1 (-375 3600)(-375 3550);
WIRE 16 -1 (-375 3550)(-675 3550);
WIRE 16 -1 (-375 3650)(-375 3600);
WIRE 16 -1 (-375 3600)(-675 3600);
WIRE 16 -1 (-375 3700)(-375 3650);
WIRE 16 -1 (-375 3650)(-675 3650);
WIRE 16 -1 (-375 3750)(-375 3700);
WIRE 16 -1 (-375 3700)(-675 3700);
WIRE 16 -1 (-375 3800)(-375 3750);
WIRE 16 -1 (-375 3750)(-675 3750);
WIRE 16 -1 (-375 3850)(-375 3800);
WIRE 16 -1 (-375 3800)(-675 3800);
WIRE 16 -1 (-375 3900)(-375 3850);
WIRE 16 -1 (-375 3850)(-675 3850);
WIRE 16 -1 (-375 3950)(-375 3900);
WIRE 16 -1 (-375 3900)(-675 3900);
WIRE 16 -1 (-375 4000)(-375 3950);
WIRE 16 -1 (-375 3950)(-675 3950);
WIRE 16 -1 (-375 4050)(-375 4000);
WIRE 16 -1 (-375 4000)(-675 4000);
WIRE 16 -1 (-375 4100)(-375 4050);
WIRE 16 -1 (-375 4050)(-675 4050);
WIRE 16 -1 (-375 4150)(-375 4100);
WIRE 16 -1 (-375 4100)(-675 4100);
WIRE 16 -1 (-375 4200)(-375 4150);
WIRE 16 -1 (-375 4150)(-675 4150);
WIRE 16 -1 (-375 4250)(-375 4200);
WIRE 16 -1 (-375 4200)(-675 4200);
WIRE 16 -1 (-375 4300)(-375 4250);
WIRE 16 -1 (-375 4250)(-675 4250);
WIRE 16 -1 (-375 4350)(-375 4300);
WIRE 16 -1 (-375 4300)(-675 4300);
WIRE 16 -1 (-375 4400)(-375 4350);
WIRE 16 -1 (-375 4350)(-675 4350);
WIRE 16 -1 (-375 4450)(-375 4400);
WIRE 16 -1 (-375 4400)(-675 4400);
WIRE 16 -1 (-375 4500)(-375 4450);
WIRE 16 -1 (-375 4450)(-675 4450);
WIRE 16 -1 (-375 4550)(-375 4500);
WIRE 16 -1 (-375 4500)(-675 4500);
WIRE 16 -1 (-375 4600)(-375 4550);
WIRE 16 -1 (-375 4550)(-675 4550);
WIRE 16 -1 (-375 4650)(-375 4600);
WIRE 16 -1 (-375 4600)(-675 4600);
WIRE 16 -1 (-375 4700)(-375 4650);
WIRE 16 -1 (-375 4650)(-675 4650);
WIRE 16 -1 (-375 4750)(-375 4700);
WIRE 16 -1 (-375 4700)(-675 4700);
WIRE 16 -1 (-375 4800)(-375 4750);
WIRE 16 -1 (-375 4750)(-675 4750);
WIRE 16 -1 (-375 4850)(-375 4800);
WIRE 16 -1 (-375 4800)(-675 4800);
WIRE 16 -1 (-375 4900)(-375 4850);
WIRE 16 -1 (-375 4850)(-675 4850);
WIRE 16 -1 (-375 4950)(-375 4900);
WIRE 16 -1 (-375 4900)(-675 4900);
WIRE 16 -1 (-375 5000)(-375 4950);
WIRE 16 -1 (-375 4950)(-675 4950);
WIRE 16 -1 (-375 5050)(-375 5000);
WIRE 16 -1 (-375 5000)(-675 5000);
WIRE 16 -1 (-375 5100)(-375 5050);
WIRE 16 -1 (-375 5050)(-675 5050);
WIRE 16 -1 (-375 5150)(-375 5100);
WIRE 16 -1 (-375 5100)(-675 5100);
WIRE 16 -1 (-375 5200)(-375 5150);
WIRE 16 -1 (-375 5150)(-675 5150);
WIRE 16 -1 (-375 5250)(-375 5200);
WIRE 16 -1 (-375 5200)(-675 5200);
WIRE 16 -1 (-375 5300)(-375 5250);
WIRE 16 -1 (-375 5250)(-675 5250);
WIRE 16 -1 (-375 5350)(-375 5300);
WIRE 16 -1 (-375 5300)(-675 5300);
WIRE 16 -1 (-375 5400)(-375 5350);
WIRE 16 -1 (-375 5350)(-675 5350);
WIRE 16 -1 (-375 5450)(-375 5400);
WIRE 16 -1 (-375 5400)(-675 5400);
WIRE 16 -1 (-375 5500)(-375 5450);
WIRE 16 -1 (-375 5450)(-675 5450);
WIRE 16 -1 (-375 5550)(-375 5500);
WIRE 16 -1 (-375 5500)(-675 5500);
WIRE 16 -1 (-375 5600)(-375 5550);
WIRE 16 -1 (-375 5550)(-675 5550);
WIRE 16 -1 (-375 5650)(-375 5600);
WIRE 16 -1 (-375 5600)(-675 5600);
WIRE 16 -1 (-375 5650)(-675 5650);
WIRE 16 -1 (-1875 2400)(-2175 2400);
WIRE 16 -1 (-2175 2450)(-2175 2400);
WIRE 16 -1 (-2175 2400)(-2175 2300);
WIRE 16 -1 (-1875 2450)(-2175 2450);
WIRE 16 -1 (-2175 2500)(-2175 2450);
WIRE 16 -1 (-1875 2500)(-2175 2500);
WIRE 16 -1 (-2175 2550)(-2175 2500);
WIRE 16 -1 (-1875 2550)(-2175 2550);
WIRE 16 -1 (-2175 2600)(-2175 2550);
WIRE 16 -1 (-1875 2600)(-2175 2600);
WIRE 16 -1 (-2175 2650)(-2175 2600);
WIRE 16 -1 (-1875 2650)(-2175 2650);
WIRE 16 -1 (-2175 2700)(-2175 2650);
WIRE 16 -1 (-1875 2700)(-2175 2700);
WIRE 16 -1 (-2175 2750)(-2175 2700);
WIRE 16 -1 (-1875 2750)(-2175 2750);
WIRE 16 -1 (-2175 2800)(-2175 2750);
WIRE 16 -1 (-1875 2800)(-2175 2800);
WIRE 16 -1 (-2175 2850)(-2175 2800);
WIRE 16 -1 (-1875 2850)(-2175 2850);
WIRE 16 -1 (-2175 2900)(-2175 2850);
WIRE 16 -1 (-1875 2900)(-2175 2900);
WIRE 16 -1 (-2175 2950)(-2175 2900);
WIRE 16 -1 (-1875 2950)(-2175 2950);
WIRE 16 -1 (-2175 3000)(-2175 2950);
WIRE 16 -1 (-1875 3000)(-2175 3000);
WIRE 16 -1 (-2175 3050)(-2175 3000);
WIRE 16 -1 (-1875 3050)(-2175 3050);
WIRE 16 -1 (-2175 3100)(-2175 3050);
WIRE 16 -1 (-1875 3100)(-2175 3100);
WIRE 16 -1 (-2175 3150)(-2175 3100);
WIRE 16 -1 (-1875 3150)(-2175 3150);
WIRE 16 -1 (-2175 3200)(-2175 3150);
WIRE 16 -1 (-1875 3200)(-2175 3200);
WIRE 16 -1 (-2175 3250)(-2175 3200);
WIRE 16 -1 (-1875 3250)(-2175 3250);
WIRE 16 -1 (-2175 3300)(-2175 3250);
WIRE 16 -1 (-1875 3300)(-2175 3300);
WIRE 16 -1 (-2175 3350)(-2175 3300);
WIRE 16 -1 (-1875 3350)(-2175 3350);
WIRE 16 -1 (-2175 3400)(-2175 3350);
WIRE 16 -1 (-1875 3400)(-2175 3400);
WIRE 16 -1 (-2175 3450)(-2175 3400);
WIRE 16 -1 (-1875 3450)(-2175 3450);
WIRE 16 -1 (-2175 3500)(-2175 3450);
WIRE 16 -1 (-1875 3500)(-2175 3500);
WIRE 16 -1 (-2175 3550)(-2175 3500);
WIRE 16 -1 (-1875 3550)(-2175 3550);
WIRE 16 -1 (-2175 3600)(-2175 3550);
WIRE 16 -1 (-1875 3600)(-2175 3600);
WIRE 16 -1 (-2175 3650)(-2175 3600);
WIRE 16 -1 (-1875 3650)(-2175 3650);
WIRE 16 -1 (-2175 3700)(-2175 3650);
WIRE 16 -1 (-1875 3700)(-2175 3700);
WIRE 16 -1 (-2175 3750)(-2175 3700);
WIRE 16 -1 (-1875 3750)(-2175 3750);
WIRE 16 -1 (-2175 3800)(-2175 3750);
WIRE 16 -1 (-1875 3800)(-2175 3800);
WIRE 16 -1 (-2175 3850)(-2175 3800);
WIRE 16 -1 (-1875 3850)(-2175 3850);
WIRE 16 -1 (-2175 3900)(-2175 3850);
WIRE 16 -1 (-1875 3900)(-2175 3900);
WIRE 16 -1 (-2175 3950)(-2175 3900);
WIRE 16 -1 (-1875 3950)(-2175 3950);
WIRE 16 -1 (-2175 4000)(-2175 3950);
WIRE 16 -1 (-1875 4000)(-2175 4000);
WIRE 16 -1 (-2175 4050)(-2175 4000);
WIRE 16 -1 (-2175 4100)(-2175 4050);
WIRE 16 -1 (-1875 4050)(-2175 4050);
WIRE 16 -1 (-1875 4100)(-2175 4100);
WIRE 16 -1 (-2175 4150)(-2175 4100);
WIRE 16 -1 (-1875 4150)(-2175 4150);
WIRE 16 -1 (-2175 4200)(-2175 4150);
WIRE 16 -1 (-1875 4200)(-2175 4200);
WIRE 16 -1 (-2175 4250)(-2175 4200);
WIRE 16 -1 (-1875 4250)(-2175 4250);
WIRE 16 -1 (-2175 4300)(-2175 4250);
WIRE 16 -1 (-1875 4300)(-2175 4300);
WIRE 16 -1 (-2175 4350)(-2175 4300);
WIRE 16 -1 (-1875 4350)(-2175 4350);
WIRE 16 -1 (-2175 4400)(-2175 4350);
WIRE 16 -1 (-1875 4400)(-2175 4400);
WIRE 16 -1 (-2175 4450)(-2175 4400);
WIRE 16 -1 (-1875 4450)(-2175 4450);
WIRE 16 -1 (-2175 4500)(-2175 4450);
WIRE 16 -1 (-1875 4500)(-2175 4500);
WIRE 16 -1 (-2175 4550)(-2175 4500);
WIRE 16 -1 (-1875 4550)(-2175 4550);
WIRE 16 -1 (-2175 4600)(-2175 4550);
WIRE 16 -1 (-1875 4600)(-2175 4600);
WIRE 16 -1 (-2175 4650)(-2175 4600);
WIRE 16 -1 (-1875 4650)(-2175 4650);
WIRE 16 -1 (-2175 4700)(-2175 4650);
WIRE 16 -1 (-1875 4700)(-2175 4700);
WIRE 16 -1 (-2175 4750)(-2175 4700);
WIRE 16 -1 (-1875 4750)(-2175 4750);
WIRE 16 -1 (-2175 4800)(-2175 4750);
WIRE 16 -1 (-1875 4800)(-2175 4800);
WIRE 16 -1 (-2175 4850)(-2175 4800);
WIRE 16 -1 (-1875 4850)(-2175 4850);
WIRE 16 -1 (-2175 4900)(-2175 4850);
WIRE 16 -1 (-1875 4900)(-2175 4900);
WIRE 16 -1 (-2175 4950)(-2175 4900);
WIRE 16 -1 (-1875 4950)(-2175 4950);
WIRE 16 -1 (-2175 5000)(-2175 4950);
WIRE 16 -1 (-1875 5000)(-2175 5000);
WIRE 16 -1 (-2175 5050)(-2175 5000);
WIRE 16 -1 (-1875 5050)(-2175 5050);
WIRE 16 -1 (-2175 5100)(-2175 5050);
WIRE 16 -1 (-1875 5100)(-2175 5100);
WIRE 16 -1 (-2175 5150)(-2175 5100);
WIRE 16 -1 (-1875 5150)(-2175 5150);
WIRE 16 -1 (-2175 5200)(-2175 5150);
WIRE 16 -1 (-1875 5200)(-2175 5200);
WIRE 16 -1 (-2175 5250)(-2175 5200);
WIRE 16 -1 (-1875 5250)(-2175 5250);
WIRE 16 -1 (-2175 5300)(-2175 5250);
WIRE 16 -1 (-1875 5300)(-2175 5300);
WIRE 16 -1 (-2175 5350)(-2175 5300);
WIRE 16 -1 (-1875 5350)(-2175 5350);
WIRE 16 -1 (-2175 5400)(-2175 5350);
WIRE 16 -1 (-1875 5400)(-2175 5400);
WIRE 16 -1 (-2175 5450)(-2175 5400);
WIRE 16 -1 (-1875 5450)(-2175 5450);
WIRE 16 -1 (-2175 5500)(-2175 5450);
WIRE 16 -1 (-1875 5500)(-2175 5500);
WIRE 16 -1 (-3675 3725)(-3525 3725);
WIRE 16 -1 (-3675 3675)(-3325 3675);
WIRE 16 -1 (-3675 4775)(-3525 4775);
WIRE 16 -1 (-3675 4725)(-3325 4725);
WIRE 16 -1 (-3525 4675)(-3675 4675);
WIRE 16 -1 (-3675 4625)(-3325 4625);
WIRE 16 -1 (-3675 3475)(-3325 3475);
WIRE 16 -1 (-3525 4575)(-3675 4575);
WIRE 16 -1 (-3525 3425)(-3675 3425);
WIRE 16 -1 (-3675 3375)(-3325 3375);
WIRE 16 -1 (-3675 4425)(-3325 4425);
WIRE 16 -1 (-3675 3325)(-3525 3325);
WIRE 16 -1 (-3675 3275)(-3325 3275);
WIRE 16 -1 (-3675 4375)(-3525 4375);
WIRE 16 -1 (-3675 4325)(-3325 4325);
WIRE 16 -1 (-3525 3225)(-3675 3225);
WIRE 16 -1 (-3675 3175)(-3325 3175);
WIRE 16 -1 (-3525 4275)(-3675 4275);
WIRE 16 -1 (-3675 4225)(-3325 4225);
WIRE 16 -1 (-3525 3125)(-3675 3125);
WIRE 16 -1 (-3675 3075)(-3325 3075);
WIRE 16 -1 (-3525 4175)(-3675 4175);
WIRE 16 -1 (-3675 4125)(-3325 4125);
WIRE 16 -1 (-3525 3025)(-3675 3025);
WIRE 16 -1 (-3675 2975)(-3325 2975);
WIRE 16 -1 (-3525 4075)(-3675 4075);
WIRE 16 -1 (-3675 4025)(-3325 4025);
WIRE 16 -1 (-3675 2925)(-3525 2925);
WIRE 16 -1 (-3675 2875)(-3325 2875);
WIRE 16 -1 (-3675 3975)(-3525 3975);
WIRE 16 -1 (-3675 3925)(-3325 3925);
WIRE 16 -1 (-3525 2825)(-3675 2825);
WIRE 16 -1 (-3675 2775)(-3325 2775);
WIRE 16 -1 (-3525 3875)(-3675 3875);
WIRE 16 -1 (-3675 3825)(-3325 3825);
WIRE 16 -1 (-3525 3525)(-3675 3525);
WIRE 16 -1 (-3675 3575)(-3325 3575);
WIRE 16 -1 (-3525 3625)(-3675 3625);
WIRE 16 -1 (-3525 4475)(-3675 4475);
WIRE 16 -1 (-3675 4525)(-3325 4525);
WIRE 16 -1 (-7625 2400)(-8200 2400);
FORCEPROP 2 LAST SIG_NAME TP_CHE_CPU1_DIMM_RFU_0
J 0
(-8210 2410);
DISPLAY 0.489362 (-8210 2410);
FORCEPROP 2 LASTPROP $XRERR UNIQUE?
J 0
(-8440 2400);
DISPLAY 0.638298 (-8440 2400);
PAINT MONO (-8440 2400);
DISPLAY INVISIBLE (-8440 2400);
WIRE 16 -1 (-7625 2450)(-8200 2450);
FORCEPROP 2 LAST SIG_NAME TP_CHE_CPU1_DIMM_RFU_1
J 0
(-8210 2460);
DISPLAY 0.489362 (-8210 2460);
FORCEPROP 2 LASTPROP $XRERR UNIQUE?
J 0
(-8440 2450);
DISPLAY 0.638298 (-8440 2450);
PAINT MONO (-8440 2450);
DISPLAY INVISIBLE (-8440 2450);
WIRE 16 -1 (-7625 2500)(-8200 2500);
FORCEPROP 2 LAST SIG_NAME TP_CHE_CPU1_DIMM_RFU_2
J 0
(-8210 2510);
DISPLAY 0.489362 (-8210 2510);
FORCEPROP 2 LASTPROP $XRERR UNIQUE?
J 0
(-8440 2500);
DISPLAY 0.638298 (-8440 2500);
PAINT MONO (-8440 2500);
DISPLAY INVISIBLE (-8440 2500);
WIRE 16 -1 (-7625 2550)(-8200 2550);
FORCEPROP 2 LAST SIG_NAME TP_CHE_CPU1_DIMM_RFU_3
J 0
(-8210 2560);
DISPLAY 0.489362 (-8210 2560);
FORCEPROP 2 LASTPROP $XRERR UNIQUE?
J 0
(-8440 2550);
DISPLAY 0.638298 (-8440 2550);
PAINT MONO (-8440 2550);
DISPLAY INVISIBLE (-8440 2550);
WIRE 16 -1 (-7625 2600)(-8200 2600);
FORCEPROP 2 LAST SIG_NAME TP_CHE_CPU1_DIMM_RFU_4
J 0
(-8210 2610);
DISPLAY 0.489362 (-8210 2610);
FORCEPROP 2 LASTPROP $XRERR UNIQUE?
J 0
(-8440 2600);
DISPLAY 0.638298 (-8440 2600);
PAINT MONO (-8440 2600);
DISPLAY INVISIBLE (-8440 2600);
WIRE 16 -1 (-7625 2650)(-8200 2650);
FORCEPROP 2 LAST SIG_NAME TP_CHE_CPU1_DIMM_RFU_5
J 0
(-8210 2660);
DISPLAY 0.489362 (-8210 2660);
FORCEPROP 2 LASTPROP $XRERR UNIQUE?
J 0
(-8440 2650);
DISPLAY 0.638298 (-8440 2650);
PAINT MONO (-8440 2650);
DISPLAY INVISIBLE (-8440 2650);
WIRE 16 -1 (-7625 4800)(-8425 4800);
FORCEPROP 2 LAST SIG_NAME M_E_CPU1_SB_PAR
J 0
(-8375 4810);
DISPLAY 0.489362 (-8375 4810);
WIRE 16 -1 (-7625 4850)(-8425 4850);
FORCEPROP 2 LAST SIG_NAME M_E_CPU1_SA_PAR
J 0
(-8375 4860);
DISPLAY 0.489362 (-8375 4860);
WIRE 16 -1 (-7625 2200)(-8425 2200);
FORCEPROP 2 LAST SIG_NAME M_E_CPU1_SB_RSP<0>
J 0
(-8375 2210);
DISPLAY 0.489362 (-8375 2210);
WIRE 16 -1 (-6225 2450)(-6425 2450);
WIRE 16 -1 (-6225 2500)(-6425 2500);
WIRE 16 -1 (-6225 2550)(-6425 2550);
WIRE 16 -1 (-6425 2600)(-6225 2600);
WIRE 16 -1 (-6225 2650)(-6425 2650);
WIRE 16 -1 (-6225 2700)(-6425 2700);
WIRE 16 -1 (-6225 2750)(-6425 2750);
WIRE 16 -1 (-6425 2800)(-6225 2800);
WIRE 16 -1 (-6225 2850)(-6425 2850);
WIRE 16 -1 (-6225 2900)(-6425 2900);
WIRE 16 -1 (-6225 2950)(-6425 2950);
WIRE 16 -1 (-6425 3000)(-6225 3000);
WIRE 16 -1 (-6225 3050)(-6425 3050);
WIRE 16 -1 (-6225 3100)(-6425 3100);
WIRE 16 -1 (-6225 3150)(-6425 3150);
WIRE 16 -1 (-6425 3200)(-6225 3200);
WIRE 16 -1 (-6225 3250)(-6425 3250);
WIRE 16 -1 (-6225 3300)(-6425 3300);
WIRE 16 -1 (-6225 3350)(-6425 3350);
WIRE 16 -1 (-6425 3400)(-6225 3400);
WIRE 16 -1 (-6225 3450)(-6425 3450);
WIRE 16 -1 (-6225 3500)(-6425 3500);
WIRE 16 -1 (-6225 3550)(-6425 3550);
WIRE 16 -1 (-6425 3600)(-6225 3600);
WIRE 16 -1 (-6225 3650)(-6425 3650);
WIRE 16 -1 (-6225 3700)(-6425 3700);
WIRE 16 -1 (-6225 3750)(-6425 3750);
WIRE 16 -1 (-6425 3800)(-6225 3800);
WIRE 16 -1 (-6225 3850)(-6425 3850);
WIRE 16 -1 (-6225 3900)(-6425 3900);
WIRE 16 -1 (-6225 3950)(-6425 3950);
WIRE 16 -1 (-6425 4000)(-6225 4000);
WIRE 16 -1 (-6225 4100)(-6425 4100);
WIRE 16 -1 (-6225 4150)(-6425 4150);
WIRE 16 -1 (-6225 4200)(-6425 4200);
WIRE 16 -1 (-6425 4250)(-6225 4250);
WIRE 16 -1 (-6225 4300)(-6425 4300);
WIRE 16 -1 (-6225 4350)(-6425 4350);
WIRE 16 -1 (-6225 4400)(-6425 4400);
WIRE 16 -1 (-6425 4450)(-6225 4450);
WIRE 16 -1 (-6225 4500)(-6425 4500);
WIRE 16 -1 (-6225 4550)(-6425 4550);
WIRE 16 -1 (-6225 4600)(-6425 4600);
WIRE 16 -1 (-6425 4650)(-6225 4650);
WIRE 16 -1 (-6225 4700)(-6425 4700);
WIRE 16 -1 (-6225 4750)(-6425 4750);
WIRE 16 -1 (-6225 4800)(-6425 4800);
WIRE 16 -1 (-6425 4850)(-6225 4850);
WIRE 16 -1 (-6225 4900)(-6425 4900);
WIRE 16 -1 (-6225 4950)(-6425 4950);
WIRE 16 -1 (-6225 5000)(-6425 5000);
WIRE 16 -1 (-6425 5050)(-6225 5050);
WIRE 16 -1 (-6225 5100)(-6425 5100);
WIRE 16 -1 (-6225 5150)(-6425 5150);
WIRE 16 -1 (-6225 5200)(-6425 5200);
WIRE 16 -1 (-6425 5250)(-6225 5250);
WIRE 16 -1 (-6225 5300)(-6425 5300);
WIRE 16 -1 (-6225 5350)(-6425 5350);
WIRE 16 -1 (-6225 5400)(-6425 5400);
WIRE 16 -1 (-6425 5450)(-6225 5450);
WIRE 16 -1 (-6225 5500)(-6425 5500);
WIRE 16 -1 (-6225 5550)(-6425 5550);
WIRE 16 -1 (-6225 5600)(-6425 5600);
WIRE 16 -1 (-7625 4550)(-8425 4550);
FORCEPROP 2 LAST SIG_NAME M_E_CPU1_SB_CS_N<1>
J 0
(-8375 4560);
DISPLAY 0.489362 (-8375 4560);
WIRE 16 -1 (-7625 4700)(-8425 4700);
FORCEPROP 2 LAST SIG_NAME M_E_CPU1_SA_CS_N<1>
J 0
(-8375 4710);
DISPLAY 0.489362 (-8375 4710);
WIRE 16 -1 (-7625 4500)(-8425 4500);
FORCEPROP 2 LAST SIG_NAME M_E_CPU1_SB_CS_N<0>
J 0
(-8375 4510);
DISPLAY 0.489362 (-8375 4510);
WIRE 16 -1 (-7625 4650)(-8425 4650);
FORCEPROP 2 LAST SIG_NAME M_E_CPU1_SA_CS_N<0>
J 0
(-8375 4660);
DISPLAY 0.489362 (-8375 4660);
WIRE 16 -1 (-7625 4400)(-8425 4400);
FORCEPROP 2 LAST SIG_NAME M_E_CPU1_CLK_DP<0>
J 0
(-8375 4410);
DISPLAY 0.489362 (-8375 4410);
WIRE 16 -1 (-7625 4350)(-8425 4350);
FORCEPROP 2 LAST SIG_NAME M_E_CPU1_CLK_DN<0>
J 0
(-8375 4360);
DISPLAY 0.489362 (-8375 4360);
WIRE 16 -1 (-7625 3450)(-7825 3450);
WIRE 16 -1 (-7625 3500)(-7825 3500);
WIRE 16 -1 (-7625 3550)(-7825 3550);
WIRE 16 -1 (-7625 3600)(-7825 3600);
WIRE 16 -1 (-7625 3650)(-7825 3650);
WIRE 16 -1 (-7625 3700)(-7825 3700);
WIRE 16 -1 (-7625 3750)(-7825 3750);
WIRE 16 -1 (-7625 3900)(-7825 3900);
WIRE 16 -1 (-7625 4000)(-7825 4000);
WIRE 16 -1 (-7625 4050)(-7825 4050);
WIRE 16 -1 (-7625 4150)(-7825 4150);
WIRE 16 -1 (-7625 4200)(-7825 4200);
WIRE 16 -1 (-7625 5250)(-7825 5250);
WIRE 16 -1 (-7625 5650)(-7825 5650);
WIRE 16 -1 (-7625 5200)(-7825 5200);
WIRE 16 -1 (-7625 5600)(-7825 5600);
WIRE 16 -1 (-7625 5150)(-7825 5150);
WIRE 16 -1 (-7625 5550)(-7825 5550);
WIRE 16 -1 (-7625 5100)(-7825 5100);
WIRE 16 -1 (-7625 5500)(-7825 5500);
WIRE 16 -1 (-7625 5050)(-7825 5050);
WIRE 16 -1 (-7625 5450)(-7825 5450);
WIRE 16 -1 (-7625 5000)(-7825 5000);
WIRE 16 -1 (-7625 5400)(-7825 5400);
WIRE 16 -1 (-7625 4950)(-7825 4950);
WIRE 16 -1 (-7625 5350)(-7825 5350);
WIRE 16 -1 (-7625 3800)(-7825 3800);
WIRE 16 -1 (-7625 3950)(-7825 3950);
WIRE 16 -1 (-7625 4100)(-7825 4100);
WIRE 16 -1 (-7625 4250)(-7825 4250);
WIRE 16 -1 (-6425 5650)(-6225 5650);
WIRE 16 -1 (-6575 1650)(-6575 1575);
WIRE 16 -1 (-6575 1650)(-7300 1650);
FORCEPROP 2 LAST SIG_NAME PD_CHE_CPU1_DIMM_SAA
J 0
(-7285 1660);
DISPLAY 0.489362 (-7285 1660);
DOT 1 (-2875 6375);
DOT 1 (-2300 6375);
DOT 1 (-2875 5950);
DOT 1 (-8500 2400);
DOT 1 (-8700 3600);
DOT 1 (-2175 5650);
DOT 1 (-2175 2450);
DOT 1 (-2175 2500);
DOT 1 (-2175 2550);
DOT 1 (-2175 2400);
DOT 1 (-2175 2700);
DOT 1 (-2175 2650);
DOT 1 (-2175 2750);
DOT 1 (-2175 2600);
DOT 1 (-2175 2800);
DOT 1 (-2175 3050);
DOT 1 (-2175 2950);
DOT 1 (-2175 2850);
DOT 1 (-2175 2900);
DOT 1 (-2175 3000);
DOT 1 (-2175 3200);
DOT 1 (-2175 3300);
DOT 1 (-2175 3150);
DOT 1 (-2175 3100);
DOT 1 (-2175 3250);
DOT 1 (-2175 3550);
DOT 1 (-2175 3450);
DOT 1 (-2175 3400);
DOT 1 (-2175 3350);
DOT 1 (-2175 3500);
DOT 1 (-2175 3700);
DOT 1 (-2175 3750);
DOT 1 (-2175 3600);
DOT 1 (-2175 3650);
DOT 1 (-2175 3800);
DOT 1 (-2175 3850);
DOT 1 (-2175 4050);
DOT 1 (-2175 3900);
DOT 1 (-2175 3950);
DOT 1 (-2175 4000);
DOT 1 (-375 2300);
DOT 1 (-375 2550);
DOT 1 (-375 2500);
DOT 1 (-375 2400);
DOT 1 (-375 2350);
DOT 1 (-375 2800);
DOT 1 (-375 2700);
DOT 1 (-375 2600);
DOT 1 (-375 2650);
DOT 1 (-375 2750);
DOT 1 (-375 3000);
DOT 1 (-375 2950);
DOT 1 (-375 2850);
DOT 1 (-375 2900);
DOT 1 (-375 3050);
DOT 1 (-375 3300);
DOT 1 (-375 3200);
DOT 1 (-375 3150);
DOT 1 (-375 3100);
DOT 1 (-375 3250);
DOT 1 (-375 3550);
DOT 1 (-375 3450);
DOT 1 (-375 3400);
DOT 1 (-375 3350);
DOT 1 (-375 3500);
DOT 1 (-375 3750);
DOT 1 (-375 3700);
DOT 1 (-375 3650);
DOT 1 (-375 3600);
DOT 1 (-375 3800);
DOT 1 (-375 3850);
DOT 1 (-375 4050);
DOT 1 (-375 3950);
DOT 1 (-375 3900);
DOT 1 (-375 4000);
DOT 1 (-2175 4100);
DOT 1 (-375 4100);
DOT 1 (-2175 4200);
DOT 1 (-2175 4250);
DOT 1 (-2175 4150);
DOT 1 (-2175 4300);
DOT 1 (-2175 4350);
DOT 1 (-2175 4550);
DOT 1 (-2175 4600);
DOT 1 (-2175 4400);
DOT 1 (-2175 4450);
DOT 1 (-2175 4500);
DOT 1 (-2175 4800);
DOT 1 (-2175 4700);
DOT 1 (-2175 4850);
DOT 1 (-2175 4650);
DOT 1 (-2175 4750);
DOT 1 (-2175 5050);
DOT 1 (-2175 5000);
DOT 1 (-2175 4900);
DOT 1 (-2175 4950);
DOT 1 (-2175 5100);
DOT 1 (-2175 5250);
DOT 1 (-2175 5350);
DOT 1 (-2175 5200);
DOT 1 (-2175 5150);
DOT 1 (-2175 5300);
DOT 1 (-2175 5400);
DOT 1 (-2175 5450);
DOT 1 (-375 4300);
DOT 1 (-375 4200);
DOT 1 (-375 4150);
DOT 1 (-375 4250);
DOT 1 (-375 4350);
DOT 1 (-375 4600);
DOT 1 (-375 4500);
DOT 1 (-375 4450);
DOT 1 (-375 4400);
DOT 1 (-375 4550);
DOT 1 (-375 4800);
DOT 1 (-375 4750);
DOT 1 (-375 4650);
DOT 1 (-375 4700);
DOT 1 (-375 4850);
DOT 1 (-375 5050);
DOT 1 (-375 5000);
DOT 1 (-375 4900);
DOT 1 (-375 4950);
DOT 1 (-375 5100);
DOT 1 (-375 5350);
DOT 1 (-375 5250);
DOT 1 (-375 5200);
DOT 1 (-375 5150);
DOT 1 (-375 5300);
DOT 1 (-375 5600);
DOT 1 (-375 5500);
DOT 1 (-375 5400);
DOT 1 (-375 5450);
DOT 1 (-375 5550);
DOT 1 (-2175 5600);
QUIT
